FILE_TYPE = MACRO_DRAWING;
SET COLOR_WIRE YELLOW;
SET COLOR_PROP MONO;
SET COLOR_DOT WHITE;
SET COLOR_ARC YELLOW;
SET COLOR_BODY GREEN;
SET COLOR_NOTE MONO;
SET PROP_DISPLAY VALUE;
SET PAGE_NUMBER P213;
FORCEADD P3V3_STBY..1
(1875 4725);
FORCEPROP 3 LASTPIN (1875 4675) SIG_NAME P3V3_STBY\g
J 0
(1885 4685);
DISPLAY 0.659574 (1885 4685);
PAINT MONO (1885 4685);
DISPLAY INVISIBLE (1885 4685);
FORCEPROP 1 LAST PATH I1
J 0
(1920 4727);
DISPLAY 0.340426 (1920 4727);
PAINT GREEN (1920 4727);
DISPLAY INVISIBLE (1920 4727);
FORCEPROP 2 LAST CDS_LIB mstr_symbols
J 0
(1875 4725);
PAINT ORANGE (1875 4725);
DISPLAY INVISIBLE (1875 4725);
FORCEPROP 1 LAST SIZE 1B
J 0
(1920 4747);
DISPLAY 0.340426 (1920 4747);
PAINT GREEN (1920 4747);
DISPLAY INVISIBLE (1920 4747);
FORCEPROP 1 LAST VOLTAGE 3.3V
J 0
(1830 4682);
DISPLAY 0.340426 (1830 4682);
PAINT SKYBLUE (1830 4682);
DISPLAY INVISIBLE (1830 4682);
FORCEPROP 1 LAST BODY_TYPE PLUMBING
J 0
(1830 4682);
DISPLAY 0.340426 (1830 4682);
PAINT GREEN (1830 4682);
DISPLAY INVISIBLE (1830 4682);
FORCEPROP 1 LAST HDL_POWER P3V3_STBY
J 0
(1575 4600);
DISPLAY 0.872340 (1575 4600);
PAINT ORANGE (1575 4600);
DISPLAY INVISIBLE (1575 4600);
FORCEADD GND..1
(2425 1275);
FORCEPROP 3 LASTPIN (2425 1325) SIG_NAME GND\g
J 0
(2435 1335);
DISPLAY 0.659574 (2435 1335);
PAINT MONO (2435 1335);
DISPLAY INVISIBLE (2435 1335);
FORCEPROP 2 LAST ROOM PVCCIO_CPU1
J 0
(1850 1350);
DISPLAY 1.361702 (1850 1350);
PAINT ORANGE (1850 1350);
DISPLAY INVISIBLE (1850 1350);
FORCEPROP 1 LAST SIZE 1B
J 0
(2500 1225);
DISPLAY 1.170213 (2500 1225);
PAINT AQUA (2500 1225);
DISPLAY INVISIBLE (2500 1225);
FORCEPROP 2 LAST CDS_LIB mstr_symbols
J 0
(2425 1275);
PAINT ORANGE (2425 1275);
DISPLAY INVISIBLE (2425 1275);
FORCEPROP 1 LAST VOLTAGE 0
J 0
(2425 1275);
PAINT SKYBLUE (2425 1275);
DISPLAY INVISIBLE (2425 1275);
FORCEPROP 1 LAST PATH I10
J 0
(2500 1275);
DISPLAY 0.872340 (2500 1275);
PAINT AQUA (2500 1275);
DISPLAY INVISIBLE (2500 1275);
FORCEPROP 1 LAST BODY_TYPE PLUMBING
J 0
(2380 1232);
DISPLAY 0.340426 (2380 1232);
PAINT GREEN (2380 1232);
DISPLAY INVISIBLE (2380 1232);
FORCEPROP 1 LAST HDL_POWER GND
J 0
(2425 1425);
DISPLAY 1.170213 (2425 1425);
PAINT GREEN (2425 1425);
DISPLAY INVISIBLE (2425 1425);
FORCEADD GND..1
(-2100 2550);
FORCEPROP 3 LASTPIN (-2100 2600) SIG_NAME GND\g
J 0
(-2090 2610);
DISPLAY 0.659574 (-2090 2610);
PAINT MONO (-2090 2610);
DISPLAY INVISIBLE (-2090 2610);
FORCEPROP 2 LAST CDS_LIB mstr_symbols
J 0
(-2100 2550);
PAINT ORANGE (-2100 2550);
DISPLAY INVISIBLE (-2100 2550);
FORCEPROP 1 LAST VOLTAGE 0
J 0
(-2100 2550);
PAINT SKYBLUE (-2100 2550);
DISPLAY INVISIBLE (-2100 2550);
FORCEPROP 2 LAST ROOM PVCCIN_CPU0_VR
J 0
(-2675 2625);
DISPLAY 1.361702 (-2675 2625);
PAINT ORANGE (-2675 2625);
DISPLAY INVISIBLE (-2675 2625);
FORCEPROP 1 LAST SIZE 1B
J 0
(-2025 2500);
DISPLAY 1.170213 (-2025 2500);
PAINT AQUA (-2025 2500);
DISPLAY INVISIBLE (-2025 2500);
FORCEPROP 1 LAST PATH I100
J 0
(-2025 2550);
DISPLAY 0.872340 (-2025 2550);
PAINT AQUA (-2025 2550);
DISPLAY INVISIBLE (-2025 2550);
FORCEPROP 1 LAST BODY_TYPE PLUMBING
J 0
(-2145 2507);
DISPLAY 0.340426 (-2145 2507);
PAINT GREEN (-2145 2507);
DISPLAY INVISIBLE (-2145 2507);
FORCEPROP 1 LAST HDL_POWER GND
J 0
(-2100 2700);
DISPLAY 1.170213 (-2100 2700);
PAINT GREEN (-2100 2700);
DISPLAY INVISIBLE (-2100 2700);
FORCEADD CAP..1
(-2100 2750);
FORCEPROP 1 LAST LOCATION C4W2
J 0
(-2425 2825);
DISPLAY 0.617021 (-2425 2825);
PAINT AQUA (-2425 2825);
FORCEPROP 1 LAST VALUE 220PF
J 0
(-2425 2775);
DISPLAY 0.617021 (-2425 2775);
PAINT SKYBLUE (-2425 2775);
FORCEPROP 1 LASTPIN (-2100 2650) $PN 2
J 0
(-2090 2630);
DISPLAY 0.617021 (-2090 2630);
PAINT ORANGE (-2090 2630);
FORCEPROP 1 LAST PART_NUMBER A36096-050
J 0
(-2425 2675);
DISPLAY 0.617021 (-2425 2675);
PAINT BLUE (-2425 2675);
FORCEPROP 1 LAST MATERIAL X7R
J 0
(-2300 2725);
DISPLAY 0.617021 (-2300 2725);
PAINT SKYBLUE (-2300 2725);
FORCEPROP 1 LAST PACK_TYPE 0402LF
J 0
(-2425 2625);
DISPLAY 0.617021 (-2425 2625);
PAINT SKYBLUE (-2425 2625);
FORCEPROP 1 LAST VOLTAGE 50V
J 0
(-2425 2725);
DISPLAY 0.617021 (-2425 2725);
PAINT SKYBLUE (-2425 2725);
FORCEPROP 1 LAST TOLERANCE 10%
J 0
(-2250 2775);
DISPLAY 0.617021 (-2250 2775);
PAINT SKYBLUE (-2250 2775);
FORCEPROP 1 LASTPIN (-2100 2850) $PN 1
J 0
(-2090 2830);
DISPLAY 0.617021 (-2090 2830);
PAINT ORANGE (-2090 2830);
FORCEPROP 0 LAST CDS_SEC 1
J 0
(-2050 2900);
PAINT MONO (-2050 2900);
DISPLAY INVISIBLE (-2050 2900);
FORCEPROP 2 LAST CDS_LIB mstr_discrete
J 0
(-2100 2750);
PAINT ORANGE (-2100 2750);
DISPLAY INVISIBLE (-2100 2750);
FORCEPROP 2 LAST ROOM PVCCIN_CPU0_VR
J 0
(-2050 2900);
DISPLAY 1.361702 (-2050 2900);
PAINT ORANGE (-2050 2900);
DISPLAY INVISIBLE (-2050 2900);
FORCEPROP 2 LAST SEC 1
J 0
(-2050 2950);
DISPLAY 0.680851 (-2050 2950);
PAINT MONO (-2050 2950);
DISPLAY INVISIBLE (-2050 2950);
FORCEPROP 2 LAST SEC_TYPE 0402LF
J 0
(-2050 2950);
DISPLAY 1.021277 (-2050 2950);
PAINT ORANGE (-2050 2950);
DISPLAY INVISIBLE (-2050 2950);
FORCEPROP 1 LAST PATH I101
J 0
(-2050 2900);
DISPLAY 0.978723 (-2050 2900);
PAINT WHITE (-2050 2900);
DISPLAY INVISIBLE (-2050 2900);
FORCEPROP 2 LAST CDS_LOCATION C4W2
J 0
(-2050 2850);
DISPLAY 0.617021 (-2050 2850);
PAINT AQUA (-2050 2850);
DISPLAY INVISIBLE (-2050 2850);
FORCEADD RES..2
(-525 1175);
FORCEPROP 1 LAST PACK_TYPE 0402
J 0
(-485 1000);
DISPLAY 0.617021 (-485 1000);
PAINT SKYBLUE (-485 1000);
FORCEPROP 1 LASTPIN (-525 1275) $PN 1
J 0
(-520 1237);
DISPLAY 0.617021 (-520 1237);
PAINT WHITE (-520 1237);
FORCEPROP 1 LASTPIN (-525 1075) $PN 2
J 0
(-520 1085);
DISPLAY 0.617021 (-520 1085);
PAINT WHITE (-520 1085);
FORCEPROP 1 LAST WATTAGE 1/16W
J 0
(-485 1150);
DISPLAY 0.617021 (-485 1150);
PAINT SKYBLUE (-485 1150);
FORCEPROP 1 LAST VALUE 3.16K
J 0
(-480 1250);
DISPLAY 0.617021 (-480 1250);
PAINT SKYBLUE (-480 1250);
FORCEPROP 1 LAST LOCATION R4E2
J 0
(-480 1300);
DISPLAY 0.617021 (-480 1300);
PAINT AQUA (-480 1300);
FORCEPROP 1 LAST TOLERANCE 1%
J 0
(-480 1200);
DISPLAY 0.617021 (-480 1200);
PAINT SKYBLUE (-480 1200);
FORCEPROP 1 LAST PART_NUMBER G21796-043
J 0
(-485 1050);
DISPLAY 0.617021 (-485 1050);
PAINT BLUE (-485 1050);
FORCEPROP 1 LAST MATERIAL CHIP
J 0
(-485 1100);
DISPLAY 0.617021 (-485 1100);
PAINT SKYBLUE (-485 1100);
FORCEPROP 0 LAST CDS_SEC 1
J 0
(-475 1350);
DISPLAY INVISIBLE (-475 1350);
FORCEPROP 2 LAST CDS_LIB mstr_discrete
J 0
(-525 1175);
PAINT ORANGE (-525 1175);
DISPLAY INVISIBLE (-525 1175);
FORCEPROP 0 LAST ROOM PVCCIN_CPU1_VR
J 0
(-475 1400);
DISPLAY 1.021277 (-475 1400);
PAINT ORANGE (-475 1400);
DISPLAY INVISIBLE (-475 1400);
FORCEPROP 0 LAST SEC 1
J 0
(-475 1450);
DISPLAY 0.680851 (-475 1450);
PAINT MONO (-475 1450);
DISPLAY INVISIBLE (-475 1450);
FORCEPROP 2 LAST SEC_TYPE 0402
J 0
(-475 1400);
DISPLAY 1.021277 (-475 1400);
PAINT ORANGE (-475 1400);
DISPLAY INVISIBLE (-475 1400);
FORCEPROP 1 LAST PATH I103
J 0
(-475 1350);
DISPLAY 0.978723 (-475 1350);
PAINT WHITE (-475 1350);
DISPLAY INVISIBLE (-475 1350);
FORCEPROP 2 LAST CDS_LOCATION R4E2
J 0
(-480 1300);
DISPLAY 0.617021 (-480 1300);
PAINT AQUA (-480 1300);
DISPLAY INVISIBLE (-480 1300);
FORCEADD RES..2
(-850 1175);
FORCEPROP 1 LASTPIN (-850 1275) $PN 1
J 0
(-845 1237);
DISPLAY 0.617021 (-845 1237);
PAINT WHITE (-845 1237);
FORCEPROP 1 LASTPIN (-850 1075) $PN 2
J 0
(-845 1085);
DISPLAY 0.617021 (-845 1085);
PAINT WHITE (-845 1085);
FORCEPROP 1 LAST WATTAGE 1/16W
J 0
(-810 1150);
DISPLAY 0.617021 (-810 1150);
PAINT SKYBLUE (-810 1150);
FORCEPROP 1 LAST VALUE 3.16K
J 0
(-805 1250);
DISPLAY 0.617021 (-805 1250);
PAINT SKYBLUE (-805 1250);
FORCEPROP 1 LAST LOCATION R4D64
J 0
(-805 1300);
DISPLAY 0.617021 (-805 1300);
PAINT AQUA (-805 1300);
FORCEPROP 1 LAST TOLERANCE 1%
J 0
(-805 1200);
DISPLAY 0.617021 (-805 1200);
PAINT SKYBLUE (-805 1200);
FORCEPROP 1 LAST MATERIAL CHIP
J 0
(-810 1100);
DISPLAY 0.617021 (-810 1100);
PAINT SKYBLUE (-810 1100);
FORCEPROP 1 LAST PACK_TYPE 0402
J 0
(-810 1000);
DISPLAY 0.617021 (-810 1000);
PAINT SKYBLUE (-810 1000);
FORCEPROP 1 LAST PART_NUMBER G21796-043
J 0
(-810 1050);
DISPLAY 0.617021 (-810 1050);
PAINT BLUE (-810 1050);
FORCEPROP 0 LAST CDS_SEC 1
J 0
(-800 1350);
DISPLAY INVISIBLE (-800 1350);
FORCEPROP 2 LAST CDS_LIB mstr_discrete
J 0
(-850 1175);
PAINT ORANGE (-850 1175);
DISPLAY INVISIBLE (-850 1175);
FORCEPROP 0 LAST ROOM PVCCIN_CPU1_VR
J 0
(-800 1400);
DISPLAY 1.021277 (-800 1400);
PAINT ORANGE (-800 1400);
DISPLAY INVISIBLE (-800 1400);
FORCEPROP 0 LAST SEC 1
J 0
(-800 1450);
DISPLAY 0.680851 (-800 1450);
PAINT MONO (-800 1450);
DISPLAY INVISIBLE (-800 1450);
FORCEPROP 2 LAST SEC_TYPE 0402
J 0
(-800 1400);
DISPLAY 1.021277 (-800 1400);
PAINT ORANGE (-800 1400);
DISPLAY INVISIBLE (-800 1400);
FORCEPROP 1 LAST PATH I104
J 0
(-800 1350);
DISPLAY 0.978723 (-800 1350);
PAINT WHITE (-800 1350);
DISPLAY INVISIBLE (-800 1350);
FORCEPROP 2 LAST CDS_LOCATION R4D64
J 0
(-805 1300);
DISPLAY 0.617021 (-805 1300);
PAINT AQUA (-805 1300);
DISPLAY INVISIBLE (-805 1300);
FORCEADD CAP_A..1
(-2850 4250);
FORCEPROP 1 LAST TOLERANCE 10%
J 0
(-2800 4200);
DISPLAY 0.617021 (-2800 4200);
PAINT SKYBLUE (-2800 4200);
FORCEPROP 1 LAST PART_NUMBER A36096-030
J 0
(-2800 4100);
DISPLAY 0.617021 (-2800 4100);
PAINT BLUE (-2800 4100);
FORCEPROP 1 LAST LOCATION C4D40
J 0
(-2800 4350);
DISPLAY 0.617021 (-2800 4350);
PAINT AQUA (-2800 4350);
FORCEPROP 1 LAST VALUE 0.1UF
J 0
(-2800 4300);
DISPLAY 0.617021 (-2800 4300);
PAINT SKYBLUE (-2800 4300);
FORCEPROP 1 LAST VOLTAGE 16V
J 0
(-2800 4250);
DISPLAY 0.617021 (-2800 4250);
PAINT SKYBLUE (-2800 4250);
FORCEPROP 1 LASTPIN (-2850 4150) $PN 2
J 0
(-2840 4130);
DISPLAY 0.787234 (-2840 4130);
PAINT ORANGE (-2840 4130);
FORCEPROP 1 LASTPIN (-2850 4350) $PN 1
J 0
(-2840 4330);
DISPLAY 0.787234 (-2840 4330);
PAINT ORANGE (-2840 4330);
FORCEPROP 1 LAST MATERIAL X7R
J 0
(-2800 4150);
DISPLAY 0.617021 (-2800 4150);
PAINT SKYBLUE (-2800 4150);
FORCEPROP 1 LAST PACK_TYPE 0402V
J 0
(-2800 4050);
DISPLAY 0.617021 (-2800 4050);
PAINT SKYBLUE (-2800 4050);
FORCEPROP 0 LAST CDS_LOCATION C4D40
J 0
(-2800 4400);
PAINT MONO (-2800 4400);
DISPLAY INVISIBLE (-2800 4400);
FORCEPROP 2 LAST CDS_LIB dev_discrete
J 0
(-2850 4250);
PAINT MONO (-2850 4250);
DISPLAY INVISIBLE (-2850 4250);
FORCEPROP 0 LAST BOM_COST SM_THERM
J 0
(-2800 4400);
DISPLAY 1.021277 (-2800 4400);
PAINT ORANGE (-2800 4400);
DISPLAY INVISIBLE (-2800 4400);
FORCEPROP 0 LAST ROOM CPU_FANS
J 0
(-2800 4450);
DISPLAY 1.021277 (-2800 4450);
PAINT ORANGE (-2800 4450);
DISPLAY INVISIBLE (-2800 4450);
FORCEPROP 2 LAST SEC_TYPE 0402V
J 0
(-2800 4450);
DISPLAY 1.021277 (-2800 4450);
PAINT ORANGE (-2800 4450);
DISPLAY INVISIBLE (-2800 4450);
FORCEPROP 2 LAST SEC 1
J 0
(-2800 4450);
DISPLAY 0.680851 (-2800 4450);
PAINT MONO (-2800 4450);
DISPLAY INVISIBLE (-2800 4450);
FORCEPROP 0 LAST CDS_SEC 1
J 0
(-2800 4400);
PAINT MONO (-2800 4400);
DISPLAY INVISIBLE (-2800 4400);
FORCEPROP 1 LAST PATH I105
J 0
(-2800 4400);
DISPLAY 0.978723 (-2800 4400);
PAINT WHITE (-2800 4400);
DISPLAY INVISIBLE (-2800 4400);
FORCEADD CAP_A..1
(2025 1575);
FORCEPROP 1 LAST LOCATION C4D32
J 0
(2075 1675);
DISPLAY 0.617021 (2075 1675);
PAINT AQUA (2075 1675);
FORCEPROP 1 LAST VALUE 0.1UF
J 0
(2075 1625);
DISPLAY 0.617021 (2075 1625);
PAINT SKYBLUE (2075 1625);
FORCEPROP 1 LAST PART_NUMBER A36096-030
J 0
(2075 1425);
DISPLAY 0.617021 (2075 1425);
PAINT BLUE (2075 1425);
FORCEPROP 1 LASTPIN (2025 1475) $PN 2
J 0
(2035 1455);
DISPLAY 0.617021 (2035 1455);
PAINT ORANGE (2035 1455);
FORCEPROP 1 LASTPIN (2025 1675) $PN 1
J 0
(2035 1655);
DISPLAY 0.617021 (2035 1655);
PAINT ORANGE (2035 1655);
FORCEPROP 1 LAST PACK_TYPE 0402V
J 0
(2075 1375);
DISPLAY 0.617021 (2075 1375);
PAINT SKYBLUE (2075 1375);
FORCEPROP 1 LAST MATERIAL X7R
J 0
(2075 1475);
DISPLAY 0.617021 (2075 1475);
PAINT SKYBLUE (2075 1475);
FORCEPROP 1 LAST TOLERANCE 10%
J 0
(2075 1525);
DISPLAY 0.617021 (2075 1525);
PAINT SKYBLUE (2075 1525);
FORCEPROP 1 LAST VOLTAGE 16V
J 0
(2075 1575);
DISPLAY 0.617021 (2075 1575);
PAINT SKYBLUE (2075 1575);
FORCEPROP 2 LAST CDS_LIB dev_discrete
J 0
(2025 1575);
PAINT ORANGE (2025 1575);
DISPLAY INVISIBLE (2025 1575);
FORCEPROP 2 LAST SEC 1
J 0
(2075 1800);
DISPLAY 0.680851 (2075 1800);
PAINT MONO (2075 1800);
DISPLAY INVISIBLE (2075 1800);
FORCEPROP 2 LAST SEC_TYPE 0402V
J 0
(2075 1800);
DISPLAY 1.021277 (2075 1800);
PAINT ORANGE (2075 1800);
DISPLAY INVISIBLE (2075 1800);
FORCEPROP 2 LAST CDS_SEC 1
J 0
(2075 1725);
PAINT ORANGE (2075 1725);
DISPLAY INVISIBLE (2075 1725);
FORCEPROP 2 LAST CDS_LOCATION C4D32
J 0
(2075 1675);
DISPLAY 0.617021 (2075 1675);
PAINT AQUA (2075 1675);
DISPLAY INVISIBLE (2075 1675);
FORCEPROP 2 LAST ROOM PVCCIO_CPU1
J 0
(2075 1725);
DISPLAY 1.361702 (2075 1725);
PAINT ORANGE (2075 1725);
DISPLAY INVISIBLE (2075 1725);
FORCEPROP 1 LAST PATH I11
J 0
(2075 1725);
DISPLAY 0.978723 (2075 1725);
PAINT WHITE (2075 1725);
DISPLAY INVISIBLE (2075 1725);
FORCEADD GND..1
(2025 1375);
FORCEPROP 3 LASTPIN (2025 1425) SIG_NAME GND\g
J 0
(2035 1435);
DISPLAY 0.659574 (2035 1435);
PAINT MONO (2035 1435);
DISPLAY INVISIBLE (2035 1435);
FORCEPROP 2 LAST ROOM PVCCIO_CPU1
J 0
(1450 1450);
DISPLAY 1.361702 (1450 1450);
PAINT ORANGE (1450 1450);
DISPLAY INVISIBLE (1450 1450);
FORCEPROP 2 LAST CDS_LIB mstr_symbols
J 0
(2025 1375);
PAINT ORANGE (2025 1375);
DISPLAY INVISIBLE (2025 1375);
FORCEPROP 1 LAST VOLTAGE 0
J 0
(2025 1375);
PAINT SKYBLUE (2025 1375);
DISPLAY INVISIBLE (2025 1375);
FORCEPROP 1 LAST SIZE 1B
J 0
(2100 1325);
DISPLAY 1.170213 (2100 1325);
PAINT AQUA (2100 1325);
DISPLAY INVISIBLE (2100 1325);
FORCEPROP 1 LAST PATH I12
J 0
(2100 1375);
DISPLAY 0.872340 (2100 1375);
PAINT AQUA (2100 1375);
DISPLAY INVISIBLE (2100 1375);
FORCEPROP 1 LAST BODY_TYPE PLUMBING
J 0
(1980 1332);
DISPLAY 0.340426 (1980 1332);
PAINT GREEN (1980 1332);
DISPLAY INVISIBLE (1980 1332);
FORCEPROP 1 LAST HDL_POWER GND
J 0
(2025 1525);
DISPLAY 1.170213 (2025 1525);
PAINT GREEN (2025 1525);
DISPLAY INVISIBLE (2025 1525);
FORCEADD RES..1
(1950 3575);
FORCEPROP 1 LAST PART_NUMBER G21796-250
J 0
(1900 3675);
DISPLAY 0.617021 (1900 3675);
PAINT BLUE (1900 3675);
FORCEPROP 1 LAST LOCATION R4D46
J 0
(1900 3625);
DISPLAY 0.617021 (1900 3625);
PAINT AQUA (1900 3625);
FORCEPROP 1 LASTPIN (1850 3575) $PN 1
J 0
(1862 3587);
DISPLAY 0.617021 (1862 3587);
PAINT ORANGE (1862 3587);
FORCEPROP 1 LAST VALUE 22.1
J 2
(1925 3475);
DISPLAY 0.617021 (1925 3475);
PAINT SKYBLUE (1925 3475);
FORCEPROP 1 LAST WATTAGE 1/16W
J 2
(1925 3425);
DISPLAY 0.617021 (1925 3425);
PAINT SKYBLUE (1925 3425);
FORCEPROP 1 LAST MATERIAL CHIP
J 0
(1950 3425);
DISPLAY 0.617021 (1950 3425);
PAINT SKYBLUE (1950 3425);
FORCEPROP 1 LAST TOLERANCE 1.0%
J 0
(1950 3475);
DISPLAY 0.617021 (1950 3475);
PAINT SKYBLUE (1950 3475);
FORCEPROP 1 LASTPIN (2050 3575) $PN 2
J 0
(2012 3587);
DISPLAY 0.617021 (2012 3587);
PAINT ORANGE (2012 3587);
FORCEPROP 1 LAST PACK_TYPE 0402
J 0
(2200 3425);
DISPLAY 0.617021 (2200 3425);
PAINT SKYBLUE (2200 3425);
FORCEPROP 2 LAST CDS_LIB mstr_discrete
J 0
(1950 3575);
PAINT MONO (1950 3575);
DISPLAY INVISIBLE (1950 3575);
FORCEPROP 2 LAST ROOM PVCCIO_CPU1
J 0
(1900 3675);
DISPLAY 1.361702 (1900 3675);
PAINT ORANGE (1900 3675);
DISPLAY INVISIBLE (1900 3675);
FORCEPROP 1 LAST PATH I13
J 0
(1900 3725);
DISPLAY 0.978723 (1900 3725);
PAINT WHITE (1900 3725);
DISPLAY INVISIBLE (1900 3725);
FORCEPROP 2 LAST CDS_LOCATION R4D46
J 0
(1900 3625);
DISPLAY 0.617021 (1900 3625);
PAINT AQUA (1900 3625);
DISPLAY INVISIBLE (1900 3625);
FORCEPROP 2 LAST SEC 1
J 0
(1900 3775);
DISPLAY 0.680851 (1900 3775);
PAINT MONO (1900 3775);
DISPLAY INVISIBLE (1900 3775);
FORCEPROP 2 LAST SEC_TYPE 0402
J 0
(1900 3775);
DISPLAY 1.021277 (1900 3775);
PAINT ORANGE (1900 3775);
DISPLAY INVISIBLE (1900 3775);
FORCEADD RES..2
(1600 4075);
FORCEPROP 1 LAST LOCATION R6P49
J 0
(1645 4200);
DISPLAY 0.617021 (1645 4200);
PAINT AQUA (1645 4200);
FORCEPROP 1 LAST VALUE 2.26K
J 0
(1645 4150);
DISPLAY 0.617021 (1645 4150);
PAINT SKYBLUE (1645 4150);
FORCEPROP 1 LASTPIN (1600 4175) $PN 1
J 0
(1605 4137);
DISPLAY 0.617021 (1605 4137);
PAINT ORANGE (1605 4137);
FORCEPROP 1 LAST TOLERANCE 1.0%
J 0
(1645 4100);
DISPLAY 0.617021 (1645 4100);
PAINT SKYBLUE (1645 4100);
FORCEPROP 1 LAST WATTAGE 1/16W
J 0
(1640 4050);
DISPLAY 0.617021 (1640 4050);
PAINT SKYBLUE (1640 4050);
FORCEPROP 1 LAST MATERIAL EMPTY
J 0
(1640 4000);
DISPLAY 0.617021 (1640 4000);
PAINT RED (1640 4000);
FORCEPROP 1 LAST PART_NUMBER G21796-311
J 0
(1640 3950);
DISPLAY 0.617021 (1640 3950);
PAINT BLUE (1640 3950);
FORCEPROP 1 LAST PACK_TYPE 0402
J 0
(1640 3900);
DISPLAY 0.617021 (1640 3900);
PAINT SKYBLUE (1640 3900);
FORCEPROP 1 LASTPIN (1600 3975) $PN 2
J 0
(1605 3985);
DISPLAY 0.617021 (1605 3985);
PAINT ORANGE (1605 3985);
FORCEPROP 2 LAST ROOM PVCCIO_CPU1
J 0
(1650 4050);
DISPLAY 1.361702 (1650 4050);
PAINT ORANGE (1650 4050);
DISPLAY INVISIBLE (1650 4050);
FORCEPROP 2 LAST CDS_LIB mstr_discrete
J 0
(1600 4075);
PAINT ORANGE (1600 4075);
DISPLAY INVISIBLE (1600 4075);
FORCEPROP 1 LAST PATH I14
J 0
(1650 4250);
DISPLAY 0.978723 (1650 4250);
PAINT WHITE (1650 4250);
DISPLAY INVISIBLE (1650 4250);
FORCEPROP 2 LAST SEC 1
J 0
(1650 4325);
DISPLAY 0.680851 (1650 4325);
PAINT MONO (1650 4325);
DISPLAY INVISIBLE (1650 4325);
FORCEPROP 2 LAST SEC_TYPE 0402
J 0
(1650 4325);
DISPLAY 1.021277 (1650 4325);
PAINT ORANGE (1650 4325);
DISPLAY INVISIBLE (1650 4325);
FORCEADD RES..2
(950 4050);
FORCEPROP 1 LAST PART_NUMBER G21796-026
J 0
(990 3925);
DISPLAY 0.617021 (990 3925);
PAINT BLUE (990 3925);
FORCEPROP 1 LAST LOCATION R4D42
J 0
(995 4175);
DISPLAY 0.617021 (995 4175);
PAINT AQUA (995 4175);
FORCEPROP 1 LAST VALUE 1.00K
J 0
(995 4125);
DISPLAY 0.617021 (995 4125);
PAINT SKYBLUE (995 4125);
FORCEPROP 1 LASTPIN (950 3950) $PN 2
J 0
(955 3960);
DISPLAY 0.787234 (955 3960);
PAINT ORANGE (955 3960);
FORCEPROP 1 LASTPIN (950 4150) $PN 1
J 0
(955 4112);
DISPLAY 0.787234 (955 4112);
PAINT ORANGE (955 4112);
FORCEPROP 1 LAST PACK_TYPE 0402
J 0
(990 3875);
DISPLAY 0.617021 (990 3875);
PAINT SKYBLUE (990 3875);
FORCEPROP 1 LAST WATTAGE 1/16W
J 0
(990 4025);
DISPLAY 0.617021 (990 4025);
PAINT SKYBLUE (990 4025);
FORCEPROP 1 LAST MATERIAL CHIP
J 0
(990 3975);
DISPLAY 0.617021 (990 3975);
PAINT SKYBLUE (990 3975);
FORCEPROP 1 LAST TOLERANCE 1%
J 0
(995 4075);
DISPLAY 0.617021 (995 4075);
PAINT SKYBLUE (995 4075);
FORCEPROP 2 LAST SEC_TYPE 0402
J 0
(1000 4275);
DISPLAY 1.021277 (1000 4275);
PAINT ORANGE (1000 4275);
DISPLAY INVISIBLE (1000 4275);
FORCEPROP 2 LAST SEC 1
J 0
(1000 4275);
PAINT MONO (1000 4275);
DISPLAY INVISIBLE (1000 4275);
FORCEPROP 2 LAST CDS_LIB mstr_discrete
J 0
(950 4050);
PAINT ORANGE (950 4050);
DISPLAY INVISIBLE (950 4050);
FORCEPROP 2 LAST ROOM PVCCIO_CPU1
J 0
(1000 4225);
DISPLAY 1.361702 (1000 4225);
PAINT ORANGE (1000 4225);
DISPLAY INVISIBLE (1000 4225);
FORCEPROP 1 LAST PATH I15
J 0
(1000 4225);
DISPLAY 0.978723 (1000 4225);
PAINT WHITE (1000 4225);
DISPLAY INVISIBLE (1000 4225);
FORCEPROP 2 LAST CDS_LOCATION R4D42
J 0
(995 4175);
DISPLAY 0.617021 (995 4175);
PAINT AQUA (995 4175);
DISPLAY INVISIBLE (995 4175);
FORCEADD RES..1
(1450 3125);
FORCEPROP 1 LAST PACK_TYPE 0402
J 0
(1550 3075);
DISPLAY 0.617021 (1550 3075);
PAINT SKYBLUE (1550 3075);
FORCEPROP 1 LAST PART_NUMBER G21497-005
J 0
(1300 3025);
DISPLAY 0.617021 (1300 3025);
PAINT BLUE (1300 3025);
FORCEPROP 1 LAST WATTAGE 1/16W
J 2
(1350 3075);
DISPLAY 0.617021 (1350 3075);
PAINT SKYBLUE (1350 3075);
FORCEPROP 1 LAST VALUE 0.0
J 2
(1425 3075);
DISPLAY 0.617021 (1425 3075);
PAINT SKYBLUE (1425 3075);
FORCEPROP 1 LASTPIN (1550 3125) $PN 2
J 0
(1512 3137);
DISPLAY 0.617021 (1512 3137);
PAINT ORANGE (1512 3137);
FORCEPROP 1 LAST TOLERANCE 5%
J 0
(1450 3075);
DISPLAY 0.617021 (1450 3075);
PAINT SKYBLUE (1450 3075);
FORCEPROP 1 LAST LOCATION R4D56
J 0
(1400 3175);
DISPLAY 0.617021 (1400 3175);
PAINT AQUA (1400 3175);
FORCEPROP 1 LAST MATERIAL CHIP
J 0
(1675 3075);
DISPLAY 0.617021 (1675 3075);
PAINT SKYBLUE (1675 3075);
FORCEPROP 1 LASTPIN (1350 3125) $PN 1
J 0
(1362 3137);
DISPLAY 0.617021 (1362 3137);
PAINT ORANGE (1362 3137);
FORCEPROP 2 LAST SEC_TYPE 0402
J 0
(1400 3350);
DISPLAY 1.021277 (1400 3350);
PAINT ORANGE (1400 3350);
DISPLAY INVISIBLE (1400 3350);
FORCEPROP 2 LAST SEC 1
J 0
(1400 3350);
DISPLAY 0.680851 (1400 3350);
PAINT MONO (1400 3350);
DISPLAY INVISIBLE (1400 3350);
FORCEPROP 2 LAST CDS_LIB mstr_discrete
J 0
(1450 3125);
PAINT ORANGE (1450 3125);
DISPLAY INVISIBLE (1450 3125);
FORCEPROP 2 LAST CDS_LOCATION R4D56
J 0
(1400 3175);
DISPLAY 0.617021 (1400 3175);
PAINT AQUA (1400 3175);
DISPLAY INVISIBLE (1400 3175);
FORCEPROP 1 LAST PATH I16
J 0
(1400 3275);
DISPLAY 0.978723 (1400 3275);
PAINT WHITE (1400 3275);
DISPLAY INVISIBLE (1400 3275);
FORCEPROP 2 LAST ROOM PVCCIO_CPU1
J 0
(1400 3225);
DISPLAY 1.361702 (1400 3225);
PAINT ORANGE (1400 3225);
DISPLAY INVISIBLE (1400 3225);
FORCEADD CAP_A..1
(150 4150);
FORCEPROP 1 LAST MATERIAL X6S
J 0
(200 4050);
DISPLAY 0.617021 (200 4050);
PAINT SKYBLUE (200 4050);
FORCEPROP 1 LASTPIN (150 4050) $PN 2
J 0
(160 4030);
DISPLAY 0.787234 (160 4030);
PAINT ORANGE (160 4030);
FORCEPROP 1 LAST PART_NUMBER D97712-004
J 0
(200 4000);
DISPLAY 0.617021 (200 4000);
PAINT BLUE (200 4000);
FORCEPROP 1 LAST PACK_TYPE 0402V
J 0
(200 3950);
DISPLAY 0.617021 (200 3950);
PAINT SKYBLUE (200 3950);
FORCEPROP 1 LAST TOLERANCE 10%
J 0
(200 4100);
DISPLAY 0.617021 (200 4100);
PAINT SKYBLUE (200 4100);
FORCEPROP 1 LAST VOLTAGE 6.3V
J 0
(200 4150);
DISPLAY 0.617021 (200 4150);
PAINT SKYBLUE (200 4150);
FORCEPROP 1 LASTPIN (150 4250) $PN 1
J 0
(160 4230);
DISPLAY 0.787234 (160 4230);
PAINT ORANGE (160 4230);
FORCEPROP 1 LAST LOCATION C4D36
J 0
(200 4250);
DISPLAY 0.617021 (200 4250);
PAINT AQUA (200 4250);
FORCEPROP 1 LAST VALUE 1.0UF
J 0
(200 4200);
DISPLAY 0.617021 (200 4200);
PAINT SKYBLUE (200 4200);
FORCEPROP 2 LAST SEC_TYPE 0402V
J 0
(200 4350);
DISPLAY 1.021277 (200 4350);
PAINT ORANGE (200 4350);
DISPLAY INVISIBLE (200 4350);
FORCEPROP 2 LAST SEC 1
J 0
(200 4350);
DISPLAY 0.680851 (200 4350);
PAINT MONO (200 4350);
DISPLAY INVISIBLE (200 4350);
FORCEPROP 2 LAST CDS_LIB dev_discrete
J 0
(150 4150);
PAINT ORANGE (150 4150);
DISPLAY INVISIBLE (150 4150);
FORCEPROP 1 LAST PATH I17
J 0
(200 4300);
DISPLAY 0.978723 (200 4300);
PAINT WHITE (200 4300);
DISPLAY INVISIBLE (200 4300);
FORCEPROP 2 LAST CDS_LOCATION C4D36
J 0
(200 4250);
DISPLAY 0.617021 (200 4250);
PAINT AQUA (200 4250);
DISPLAY INVISIBLE (200 4250);
FORCEPROP 2 LAST ROOM PVCCIO_CPU1
J 0
(200 4300);
DISPLAY 1.361702 (200 4300);
PAINT ORANGE (200 4300);
DISPLAY INVISIBLE (200 4300);
FORCEADD GND..1
(150 3950);
FORCEPROP 3 LASTPIN (150 4000) SIG_NAME GND\g
J 0
(160 4010);
DISPLAY 0.659574 (160 4010);
PAINT MONO (160 4010);
DISPLAY INVISIBLE (160 4010);
FORCEPROP 2 LAST ROOM PVCCIO_CPU1
J 0
(-425 4025);
DISPLAY 1.361702 (-425 4025);
PAINT ORANGE (-425 4025);
DISPLAY INVISIBLE (-425 4025);
FORCEPROP 1 LAST PATH I18
J 0
(225 3950);
DISPLAY 0.872340 (225 3950);
PAINT AQUA (225 3950);
DISPLAY INVISIBLE (225 3950);
FORCEPROP 1 LAST SIZE 1B
J 0
(225 3900);
DISPLAY 1.170213 (225 3900);
PAINT AQUA (225 3900);
DISPLAY INVISIBLE (225 3900);
FORCEPROP 2 LAST CDS_LIB mstr_symbols
J 0
(150 3950);
PAINT ORANGE (150 3950);
DISPLAY INVISIBLE (150 3950);
FORCEPROP 1 LAST VOLTAGE 0
J 0
(150 3950);
PAINT SKYBLUE (150 3950);
DISPLAY INVISIBLE (150 3950);
FORCEPROP 1 LAST BODY_TYPE PLUMBING
J 0
(105 3907);
DISPLAY 0.340426 (105 3907);
PAINT GREEN (105 3907);
DISPLAY INVISIBLE (105 3907);
FORCEPROP 1 LAST HDL_POWER GND
J 0
(150 4100);
DISPLAY 1.170213 (150 4100);
PAINT GREEN (150 4100);
DISPLAY INVISIBLE (150 4100);
FORCEADD OFFPAGE..2
(2725 3575);
FORCEPROP 2 LAST $XR0 191 
J 0
(2914 3575);
DISPLAY 0.638298 (2914 3575);
PAINT MONO (2914 3575);
FORCEPROP 2 LAST ROOM PVCCIO_CPU1
J 0
(2300 3650);
DISPLAY 1.361702 (2300 3650);
PAINT ORANGE (2300 3650);
DISPLAY INVISIBLE (2300 3650);
FORCEPROP 2 LAST CDS_LIB mstr_standard
J 0
(2725 3575);
PAINT ORANGE (2725 3575);
DISPLAY INVISIBLE (2725 3575);
FORCEPROP 2 LAST PATH I2
J 0
(2900 3650);
DISPLAY 1.021277 (2900 3650);
PAINT ORANGE (2900 3650);
DISPLAY INVISIBLE (2900 3650);
FORCEPROP 1 LAST OFFPAGE TRUE
J 0
(3050 3450);
DISPLAY 1.170213 (3050 3450);
PAINT GREEN (3050 3450);
DISPLAY INVISIBLE (3050 3450);
FORCEPROP 1 LAST COMMENT_BODY TRUE
J 0
(2680 3480);
DISPLAY 1.170213 (2680 3480);
PAINT GREEN (2680 3480);
DISPLAY INVISIBLE (2680 3480);
FORCEADD GND..1
(1000 1875);
FORCEPROP 3 LASTPIN (1000 1925) SIG_NAME GND\g
J 0
(1010 1935);
DISPLAY 0.659574 (1010 1935);
PAINT MONO (1010 1935);
DISPLAY INVISIBLE (1010 1935);
FORCEPROP 2 LAST ROOM PVCCIO_CPU1
J 0
(425 1950);
DISPLAY 1.361702 (425 1950);
PAINT ORANGE (425 1950);
DISPLAY INVISIBLE (425 1950);
FORCEPROP 2 LAST CDS_LIB mstr_symbols
J 0
(1000 1875);
PAINT ORANGE (1000 1875);
DISPLAY INVISIBLE (1000 1875);
FORCEPROP 1 LAST VOLTAGE 0
J 0
(1000 1875);
PAINT SKYBLUE (1000 1875);
DISPLAY INVISIBLE (1000 1875);
FORCEPROP 1 LAST PATH I21
J 0
(1075 1875);
DISPLAY 0.872340 (1075 1875);
PAINT AQUA (1075 1875);
DISPLAY INVISIBLE (1075 1875);
FORCEPROP 1 LAST SIZE 1B
J 0
(1075 1825);
DISPLAY 1.170213 (1075 1825);
PAINT AQUA (1075 1825);
DISPLAY INVISIBLE (1075 1825);
FORCEPROP 1 LAST BODY_TYPE PLUMBING
J 0
(955 1832);
DISPLAY 0.340426 (955 1832);
PAINT GREEN (955 1832);
DISPLAY INVISIBLE (955 1832);
FORCEPROP 1 LAST HDL_POWER GND
J 0
(1000 2025);
DISPLAY 1.170213 (1000 2025);
PAINT GREEN (1000 2025);
DISPLAY INVISIBLE (1000 2025);
FORCEADD P3V3_STBY..1
(-550 4825);
FORCEPROP 3 LASTPIN (-550 4775) SIG_NAME P3V3_STBY\g
J 0
(-540 4785);
DISPLAY 0.659574 (-540 4785);
PAINT MONO (-540 4785);
DISPLAY INVISIBLE (-540 4785);
FORCEPROP 1 LAST VOLTAGE 3.3V
J 0
(-595 4782);
DISPLAY 0.340426 (-595 4782);
PAINT SKYBLUE (-595 4782);
DISPLAY INVISIBLE (-595 4782);
FORCEPROP 2 LAST CDS_LIB mstr_symbols
J 0
(-550 4825);
PAINT ORANGE (-550 4825);
DISPLAY INVISIBLE (-550 4825);
FORCEPROP 1 LAST PATH I24
J 0
(-505 4827);
DISPLAY 0.340426 (-505 4827);
PAINT GREEN (-505 4827);
DISPLAY INVISIBLE (-505 4827);
FORCEPROP 1 LAST SIZE 1B
J 0
(-505 4847);
DISPLAY 0.340426 (-505 4847);
PAINT GREEN (-505 4847);
DISPLAY INVISIBLE (-505 4847);
FORCEPROP 1 LAST BODY_TYPE PLUMBING
J 0
(-595 4782);
DISPLAY 0.340426 (-595 4782);
PAINT GREEN (-595 4782);
DISPLAY INVISIBLE (-595 4782);
FORCEPROP 1 LAST HDL_POWER P3V3_STBY
J 0
(-850 4700);
DISPLAY 0.872340 (-850 4700);
PAINT ORANGE (-850 4700);
DISPLAY INVISIBLE (-850 4700);
FORCEADD RES..2
(-550 4500);
FORCEPROP 1 LAST PACK_TYPE 0402
J 0
(-510 4325);
DISPLAY 0.617021 (-510 4325);
PAINT SKYBLUE (-510 4325);
FORCEPROP 1 LAST PART_NUMBER G21497-005
J 0
(-510 4375);
DISPLAY 0.617021 (-510 4375);
PAINT BLUE (-510 4375);
FORCEPROP 1 LAST MATERIAL CHIP
J 0
(-510 4425);
DISPLAY 0.617021 (-510 4425);
PAINT SKYBLUE (-510 4425);
FORCEPROP 1 LAST WATTAGE 1/16W
J 0
(-510 4475);
DISPLAY 0.617021 (-510 4475);
PAINT SKYBLUE (-510 4475);
FORCEPROP 1 LAST TOLERANCE 5%
J 0
(-505 4525);
DISPLAY 0.617021 (-505 4525);
PAINT SKYBLUE (-505 4525);
FORCEPROP 1 LASTPIN (-550 4400) $PN 2
J 0
(-545 4410);
DISPLAY 0.787234 (-545 4410);
PAINT ORANGE (-545 4410);
FORCEPROP 1 LASTPIN (-550 4600) $PN 1
J 0
(-545 4562);
DISPLAY 0.787234 (-545 4562);
PAINT ORANGE (-545 4562);
FORCEPROP 1 LAST VALUE 0.0
J 0
(-505 4575);
DISPLAY 0.617021 (-505 4575);
PAINT SKYBLUE (-505 4575);
FORCEPROP 1 LAST LOCATION R4D47
J 0
(-505 4625);
DISPLAY 0.617021 (-505 4625);
PAINT AQUA (-505 4625);
FORCEPROP 2 LAST SEC_TYPE 0402
J 0
(-500 4725);
DISPLAY 1.021277 (-500 4725);
PAINT ORANGE (-500 4725);
DISPLAY INVISIBLE (-500 4725);
FORCEPROP 2 LAST SEC 1
J 0
(-500 4725);
PAINT MONO (-500 4725);
DISPLAY INVISIBLE (-500 4725);
FORCEPROP 2 LAST CDS_LIB mstr_discrete
J 0
(-550 4500);
PAINT ORANGE (-550 4500);
DISPLAY INVISIBLE (-550 4500);
FORCEPROP 2 LAST ROOM PVCCIO_CPU1
J 0
(-500 4675);
DISPLAY 1.361702 (-500 4675);
PAINT ORANGE (-500 4675);
DISPLAY INVISIBLE (-500 4675);
FORCEPROP 1 LAST PATH I25
J 0
(-500 4675);
DISPLAY 0.978723 (-500 4675);
PAINT WHITE (-500 4675);
DISPLAY INVISIBLE (-500 4675);
FORCEPROP 2 LAST CDS_LOCATION R4D47
J 0
(-505 4625);
DISPLAY 0.617021 (-505 4625);
PAINT AQUA (-505 4625);
DISPLAY INVISIBLE (-505 4625);
FORCEADD PVCCIO_CPU1..1
(-1450 4900);
FORCEPROP 3 LASTPIN (-1450 4850) SIG_NAME PVCCIO_CPU1\g
J 0
(-1440 4860);
DISPLAY 0.659574 (-1440 4860);
PAINT MONO (-1440 4860);
DISPLAY INVISIBLE (-1440 4860);
FORCEPROP 1 LAST VOLTAGE 1.1V
J 0
(-1495 4857);
DISPLAY 0.340426 (-1495 4857);
PAINT SKYBLUE (-1495 4857);
DISPLAY INVISIBLE (-1495 4857);
FORCEPROP 2 LAST CDS_LIB mstr_symbols
J 0
(-1450 4900);
PAINT ORANGE (-1450 4900);
DISPLAY INVISIBLE (-1450 4900);
FORCEPROP 1 LAST PATH I26
J 0
(-1400 4925);
DISPLAY 0.872340 (-1400 4925);
PAINT AQUA (-1400 4925);
DISPLAY INVISIBLE (-1400 4925);
FORCEPROP 1 LAST BODY_TYPE PLUMBING
J 0
(-1495 4857);
DISPLAY 0.340426 (-1495 4857);
PAINT GREEN (-1495 4857);
DISPLAY INVISIBLE (-1495 4857);
FORCEPROP 1 LAST HDL_POWER PVCCIO_CPU1
J 1
(-1450 4950);
DISPLAY 0.872340 (-1450 4950);
PAINT GREEN (-1450 4950);
DISPLAY INVISIBLE (-1450 4950);
FORCEADD RES..2
(-1450 4475);
FORCEPROP 1 LAST TOLERANCE 1%
J 0
(-1405 4500);
DISPLAY 0.617021 (-1405 4500);
PAINT SKYBLUE (-1405 4500);
FORCEPROP 1 LAST VALUE 100.0
J 0
(-1405 4550);
DISPLAY 0.617021 (-1405 4550);
PAINT SKYBLUE (-1405 4550);
FORCEPROP 1 LAST LOCATION R6P35
J 0
(-1405 4600);
DISPLAY 0.617021 (-1405 4600);
PAINT AQUA (-1405 4600);
FORCEPROP 1 LAST PACK_TYPE 0402
J 0
(-1410 4300);
DISPLAY 0.617021 (-1410 4300);
PAINT SKYBLUE (-1410 4300);
FORCEPROP 1 LAST PART_NUMBER G21796-017
J 0
(-1410 4350);
DISPLAY 0.617021 (-1410 4350);
PAINT BLUE (-1410 4350);
FORCEPROP 1 LAST MATERIAL EMPTY
J 0
(-1410 4400);
DISPLAY 0.617021 (-1410 4400);
PAINT RED (-1410 4400);
FORCEPROP 1 LAST WATTAGE 1/16W
J 0
(-1410 4450);
DISPLAY 0.617021 (-1410 4450);
PAINT SKYBLUE (-1410 4450);
FORCEPROP 1 LASTPIN (-1450 4375) $PN 2
J 0
(-1445 4385);
DISPLAY 0.787234 (-1445 4385);
PAINT ORANGE (-1445 4385);
FORCEPROP 1 LASTPIN (-1450 4575) $PN 1
J 0
(-1445 4537);
DISPLAY 0.787234 (-1445 4537);
PAINT ORANGE (-1445 4537);
FORCEPROP 2 LAST SEC_TYPE 0402
J 0
(-1400 4700);
DISPLAY 1.021277 (-1400 4700);
PAINT ORANGE (-1400 4700);
DISPLAY INVISIBLE (-1400 4700);
FORCEPROP 2 LAST SEC 1
J 0
(-1400 4700);
PAINT MONO (-1400 4700);
DISPLAY INVISIBLE (-1400 4700);
FORCEPROP 2 LAST CDS_LIB mstr_discrete
J 0
(-1450 4475);
PAINT ORANGE (-1450 4475);
DISPLAY INVISIBLE (-1450 4475);
FORCEPROP 2 LAST CDS_LOCATION R6P35
J 0
(-1405 4600);
DISPLAY 0.617021 (-1405 4600);
PAINT AQUA (-1405 4600);
DISPLAY INVISIBLE (-1405 4600);
FORCEPROP 1 LAST PATH I27
J 0
(-1400 4650);
DISPLAY 0.978723 (-1400 4650);
PAINT WHITE (-1400 4650);
DISPLAY INVISIBLE (-1400 4650);
FORCEPROP 2 LAST ROOM PVCCIO_CPU1
J 0
(-1400 4650);
DISPLAY 1.361702 (-1400 4650);
PAINT ORANGE (-1400 4650);
DISPLAY INVISIBLE (-1400 4650);
FORCEADD PVCCIO_CPU1..1
(-2050 4875);
FORCEPROP 3 LASTPIN (-2050 4825) SIG_NAME PVCCIO_CPU1\g
J 0
(-2040 4835);
DISPLAY 0.659574 (-2040 4835);
PAINT MONO (-2040 4835);
DISPLAY INVISIBLE (-2040 4835);
FORCEPROP 2 LAST CDS_LIB mstr_symbols
J 0
(-2050 4875);
PAINT ORANGE (-2050 4875);
DISPLAY INVISIBLE (-2050 4875);
FORCEPROP 1 LAST VOLTAGE 1.1V
J 0
(-2095 4832);
DISPLAY 0.340426 (-2095 4832);
PAINT SKYBLUE (-2095 4832);
DISPLAY INVISIBLE (-2095 4832);
FORCEPROP 1 LAST PATH I28
J 0
(-2000 4900);
DISPLAY 0.872340 (-2000 4900);
PAINT AQUA (-2000 4900);
DISPLAY INVISIBLE (-2000 4900);
FORCEPROP 1 LAST BODY_TYPE PLUMBING
J 0
(-2095 4832);
DISPLAY 0.340426 (-2095 4832);
PAINT GREEN (-2095 4832);
DISPLAY INVISIBLE (-2095 4832);
FORCEPROP 1 LAST HDL_POWER PVCCIO_CPU1
J 1
(-2050 4925);
DISPLAY 0.872340 (-2050 4925);
PAINT GREEN (-2050 4925);
DISPLAY INVISIBLE (-2050 4925);
FORCEADD OFFPAGE..2
(2775 3125);
FORCEPROP 2 LAST $XR2 55 
J 0
(3204 3125);
DISPLAY 0.638298 (3204 3125);
PAINT MONO (3204 3125);
FORCEPROP 2 LAST $XR1 206 
J 0
(3084 3125);
DISPLAY 0.638298 (3084 3125);
PAINT MONO (3084 3125);
FORCEPROP 2 LAST $XR0 193 
J 0
(2964 3125);
DISPLAY 0.638298 (2964 3125);
PAINT MONO (2964 3125);
FORCEPROP 2 LAST ROOM PVCCIO_CPU1
J 0
(2350 3200);
DISPLAY 1.361702 (2350 3200);
PAINT ORANGE (2350 3200);
DISPLAY INVISIBLE (2350 3200);
FORCEPROP 2 LAST CDS_LIB mstr_standard
J 0
(2775 3125);
PAINT ORANGE (2775 3125);
DISPLAY INVISIBLE (2775 3125);
FORCEPROP 2 LAST PATH I3
J 0
(2950 3200);
DISPLAY 1.021277 (2950 3200);
PAINT ORANGE (2950 3200);
DISPLAY INVISIBLE (2950 3200);
FORCEPROP 1 LAST OFFPAGE TRUE
J 0
(3100 3000);
DISPLAY 1.170213 (3100 3000);
PAINT GREEN (3100 3000);
DISPLAY INVISIBLE (3100 3000);
FORCEPROP 1 LAST COMMENT_BODY TRUE
J 0
(2730 3030);
DISPLAY 1.170213 (2730 3030);
PAINT GREEN (2730 3030);
DISPLAY INVISIBLE (2730 3030);
FORCEADD RES..2
(-2050 4425);
FORCEPROP 1 LAST PART_NUMBER G21796-203
J 0
(-2010 4300);
DISPLAY 0.617021 (-2010 4300);
PAINT BLUE (-2010 4300);
FORCEPROP 1 LAST PACK_TYPE 0402
J 0
(-2010 4250);
DISPLAY 0.617021 (-2010 4250);
PAINT SKYBLUE (-2010 4250);
FORCEPROP 1 LASTPIN (-2050 4525) $PN 1
J 0
(-2045 4487);
DISPLAY 0.617021 (-2045 4487);
PAINT ORANGE (-2045 4487);
FORCEPROP 1 LAST TOLERANCE 1%
J 0
(-2005 4450);
DISPLAY 0.617021 (-2005 4450);
PAINT SKYBLUE (-2005 4450);
FORCEPROP 1 LAST WATTAGE 1/16W
J 0
(-2010 4400);
DISPLAY 0.617021 (-2010 4400);
PAINT SKYBLUE (-2010 4400);
FORCEPROP 1 LAST MATERIAL EMPTY
J 0
(-2010 4350);
DISPLAY 0.617021 (-2010 4350);
PAINT RED (-2010 4350);
FORCEPROP 1 LASTPIN (-2050 4325) $PN 2
J 0
(-2045 4335);
DISPLAY 0.617021 (-2045 4335);
PAINT ORANGE (-2045 4335);
FORCEPROP 1 LAST VALUE 110
J 0
(-2005 4500);
DISPLAY 0.617021 (-2005 4500);
PAINT SKYBLUE (-2005 4500);
FORCEPROP 1 LAST LOCATION R6P33
J 0
(-2005 4550);
DISPLAY 0.617021 (-2005 4550);
PAINT AQUA (-2005 4550);
FORCEPROP 2 LAST CDS_LIB mstr_discrete
J 0
(-2050 4425);
PAINT ORANGE (-2050 4425);
DISPLAY INVISIBLE (-2050 4425);
FORCEPROP 2 LAST CDS_LOCATION R6P33
J 0
(-2005 4550);
DISPLAY 0.617021 (-2005 4550);
PAINT AQUA (-2005 4550);
DISPLAY INVISIBLE (-2005 4550);
FORCEPROP 2 LAST ROOM PVCCIO_CPU1
J 0
(-2000 4600);
DISPLAY 1.361702 (-2000 4600);
PAINT ORANGE (-2000 4600);
DISPLAY INVISIBLE (-2000 4600);
FORCEPROP 1 LAST PATH I30
J 0
(-2000 4600);
DISPLAY 0.978723 (-2000 4600);
PAINT WHITE (-2000 4600);
DISPLAY INVISIBLE (-2000 4600);
FORCEPROP 2 LAST SEC 1
J 0
(-2000 4675);
PAINT MONO (-2000 4675);
DISPLAY INVISIBLE (-2000 4675);
FORCEPROP 2 LAST SEC_TYPE 0402
J 0
(-2000 4675);
DISPLAY 1.021277 (-2000 4675);
PAINT ORANGE (-2000 4675);
DISPLAY INVISIBLE (-2000 4675);
FORCEADD RES..2
(-2425 4700);
FORCEPROP 1 LAST WATTAGE 1/16W
J 0
(-2385 4675);
DISPLAY 0.617021 (-2385 4675);
PAINT SKYBLUE (-2385 4675);
FORCEPROP 1 LAST MATERIAL CHIP
J 0
(-2385 4625);
DISPLAY 0.617021 (-2385 4625);
PAINT SKYBLUE (-2385 4625);
FORCEPROP 1 LAST PART_NUMBER G21796-160
J 0
(-2385 4575);
DISPLAY 0.617021 (-2385 4575);
PAINT BLUE (-2385 4575);
FORCEPROP 1 LASTPIN (-2425 4600) $PN 2
J 0
(-2420 4610);
DISPLAY 0.617021 (-2420 4610);
PAINT ORANGE (-2420 4610);
FORCEPROP 1 LAST PACK_TYPE 0402
J 0
(-2385 4525);
DISPLAY 0.617021 (-2385 4525);
PAINT SKYBLUE (-2385 4525);
FORCEPROP 1 LAST TOLERANCE 1%
J 0
(-2380 4725);
DISPLAY 0.617021 (-2380 4725);
PAINT SKYBLUE (-2380 4725);
FORCEPROP 1 LAST VALUE 100.0K
J 0
(-2380 4775);
DISPLAY 0.617021 (-2380 4775);
PAINT SKYBLUE (-2380 4775);
FORCEPROP 1 LASTPIN (-2425 4800) $PN 1
J 0
(-2420 4762);
DISPLAY 0.617021 (-2420 4762);
PAINT ORANGE (-2420 4762);
FORCEPROP 1 LAST LOCATION R4D60
J 0
(-2380 4825);
DISPLAY 0.617021 (-2380 4825);
PAINT AQUA (-2380 4825);
FORCEPROP 2 LAST CDS_LOCATION R4D60
J 0
(-2380 4825);
DISPLAY 0.617021 (-2380 4825);
PAINT AQUA (-2380 4825);
DISPLAY INVISIBLE (-2380 4825);
FORCEPROP 2 LAST CDS_LIB mstr_discrete
J 0
(-2425 4700);
PAINT ORANGE (-2425 4700);
DISPLAY INVISIBLE (-2425 4700);
FORCEPROP 2 LAST ROOM PVCCIO_CPU1
J 0
(-2375 4875);
DISPLAY 1.361702 (-2375 4875);
PAINT ORANGE (-2375 4875);
DISPLAY INVISIBLE (-2375 4875);
FORCEPROP 1 LAST PATH I31
J 0
(-2375 4875);
DISPLAY 0.978723 (-2375 4875);
PAINT WHITE (-2375 4875);
DISPLAY INVISIBLE (-2375 4875);
FORCEPROP 2 LAST SEC 1
J 0
(-2375 4925);
DISPLAY 0.680851 (-2375 4925);
PAINT MONO (-2375 4925);
DISPLAY INVISIBLE (-2375 4925);
FORCEPROP 2 LAST SEC_TYPE 0402
J 0
(-2375 4925);
DISPLAY 1.021277 (-2375 4925);
PAINT ORANGE (-2375 4925);
DISPLAY INVISIBLE (-2375 4925);
FORCEADD RES..2
(-2425 4250);
FORCEPROP 1 LAST LOCATION R4D57
J 0
(-2380 4375);
DISPLAY 0.617021 (-2380 4375);
PAINT AQUA (-2380 4375);
FORCEPROP 1 LAST PACK_TYPE 0402
J 0
(-2385 4075);
DISPLAY 0.617021 (-2385 4075);
PAINT SKYBLUE (-2385 4075);
FORCEPROP 1 LASTPIN (-2425 4150) $PN 2
J 0
(-2420 4160);
DISPLAY 0.617021 (-2420 4160);
PAINT ORANGE (-2420 4160);
FORCEPROP 1 LAST MATERIAL CHIP
J 0
(-2385 4175);
DISPLAY 0.617021 (-2385 4175);
PAINT SKYBLUE (-2385 4175);
FORCEPROP 1 LAST TOLERANCE 1%
J 0
(-2380 4275);
DISPLAY 0.617021 (-2380 4275);
PAINT SKYBLUE (-2380 4275);
FORCEPROP 1 LAST VALUE 1.5K
J 0
(-2380 4325);
DISPLAY 0.617021 (-2380 4325);
PAINT SKYBLUE (-2380 4325);
FORCEPROP 1 LASTPIN (-2425 4350) $PN 1
J 0
(-2420 4312);
DISPLAY 0.617021 (-2420 4312);
PAINT ORANGE (-2420 4312);
FORCEPROP 1 LAST WATTAGE 1/16W
J 0
(-2385 4225);
DISPLAY 0.617021 (-2385 4225);
PAINT SKYBLUE (-2385 4225);
FORCEPROP 1 LAST PART_NUMBER G21796-003
J 0
(-2385 4125);
DISPLAY 0.617021 (-2385 4125);
PAINT BLUE (-2385 4125);
FORCEPROP 2 LAST CDS_LIB mstr_discrete
J 0
(-2425 4250);
PAINT ORANGE (-2425 4250);
DISPLAY INVISIBLE (-2425 4250);
FORCEPROP 2 LAST ROOM PVCCIO_CPU1
J 0
(-2375 4425);
DISPLAY 1.361702 (-2375 4425);
PAINT ORANGE (-2375 4425);
DISPLAY INVISIBLE (-2375 4425);
FORCEPROP 1 LAST PATH I32
J 0
(-2375 4425);
DISPLAY 0.978723 (-2375 4425);
PAINT WHITE (-2375 4425);
DISPLAY INVISIBLE (-2375 4425);
FORCEPROP 2 LAST CDS_LOCATION R4D57
J 0
(-2380 4375);
DISPLAY 0.617021 (-2380 4375);
PAINT AQUA (-2380 4375);
DISPLAY INVISIBLE (-2380 4375);
FORCEPROP 2 LAST SEC 1
J 0
(-2375 4475);
DISPLAY 0.680851 (-2375 4475);
PAINT MONO (-2375 4475);
DISPLAY INVISIBLE (-2375 4475);
FORCEPROP 2 LAST SEC_TYPE 0402
J 0
(-2375 4475);
DISPLAY 1.021277 (-2375 4475);
PAINT ORANGE (-2375 4475);
DISPLAY INVISIBLE (-2375 4475);
FORCEADD OFFPAGE..2
R 2
(-3250 4600);
FORCEPROP 2 LAST $XR0 213 
J 0
(-3505 4600);
DISPLAY 0.638298 (-3505 4600);
PAINT MONO (-3505 4600);
FORCEPROP 1 LAST COMMENT_BODY TRUE
J 2
(-3205 4505);
DISPLAY 1.170213 (-3205 4505);
PAINT GREEN (-3205 4505);
DISPLAY INVISIBLE (-3205 4505);
FORCEPROP 1 LAST OFFPAGE TRUE
J 2
(-3575 4475);
DISPLAY 1.170213 (-3575 4475);
PAINT GREEN (-3575 4475);
DISPLAY INVISIBLE (-3575 4475);
FORCEPROP 2 LAST CDS_LIB mstr_standard
J 2
(-3250 4600);
PAINT ORANGE (-3250 4600);
DISPLAY INVISIBLE (-3250 4600);
FORCEPROP 2 LAST PATH I34
J 0
(-3200 4675);
DISPLAY 1.021277 (-3200 4675);
PAINT ORANGE (-3200 4675);
DISPLAY INVISIBLE (-3200 4675);
FORCEPROP 2 LAST ROOM PVCCIO_CPU1
J 0
(-3800 4675);
DISPLAY 1.361702 (-3800 4675);
PAINT ORANGE (-3800 4675);
DISPLAY INVISIBLE (-3800 4675);
FORCEADD CAP_A..1
(-250 4150);
FORCEPROP 1 LAST LOCATION C4D38
J 0
(-200 4250);
DISPLAY 0.617021 (-200 4250);
PAINT AQUA (-200 4250);
FORCEPROP 1 LAST VALUE 0.1UF
J 0
(-200 4200);
DISPLAY 0.617021 (-200 4200);
PAINT SKYBLUE (-200 4200);
FORCEPROP 1 LAST VOLTAGE 16V
J 0
(-200 4150);
DISPLAY 0.617021 (-200 4150);
PAINT SKYBLUE (-200 4150);
FORCEPROP 1 LAST TOLERANCE 10%
J 0
(-200 4100);
DISPLAY 0.617021 (-200 4100);
PAINT SKYBLUE (-200 4100);
FORCEPROP 1 LAST PART_NUMBER A36096-030
J 0
(-200 4000);
DISPLAY 0.617021 (-200 4000);
PAINT BLUE (-200 4000);
FORCEPROP 1 LAST PACK_TYPE 0402V
J 0
(-200 3950);
DISPLAY 0.617021 (-200 3950);
PAINT SKYBLUE (-200 3950);
FORCEPROP 1 LAST MATERIAL X7R
J 0
(-200 4050);
DISPLAY 0.617021 (-200 4050);
PAINT SKYBLUE (-200 4050);
FORCEPROP 1 LASTPIN (-250 4250) $PN 1
J 0
(-240 4230);
DISPLAY 0.787234 (-240 4230);
PAINT ORANGE (-240 4230);
FORCEPROP 1 LASTPIN (-250 4050) $PN 2
J 0
(-240 4030);
DISPLAY 0.787234 (-240 4030);
PAINT ORANGE (-240 4030);
FORCEPROP 2 LAST SEC_TYPE 0402V
J 0
(-200 4350);
DISPLAY 1.021277 (-200 4350);
PAINT ORANGE (-200 4350);
DISPLAY INVISIBLE (-200 4350);
FORCEPROP 2 LAST SEC 1
J 0
(-200 4350);
PAINT MONO (-200 4350);
DISPLAY INVISIBLE (-200 4350);
FORCEPROP 2 LAST CDS_LIB dev_discrete
J 0
(-250 4150);
PAINT ORANGE (-250 4150);
DISPLAY INVISIBLE (-250 4150);
FORCEPROP 2 LAST CDS_LOCATION C4D38
J 0
(-200 4250);
DISPLAY 0.617021 (-200 4250);
PAINT AQUA (-200 4250);
DISPLAY INVISIBLE (-200 4250);
FORCEPROP 1 LAST PATH I35
J 0
(-200 4300);
DISPLAY 0.978723 (-200 4300);
PAINT WHITE (-200 4300);
DISPLAY INVISIBLE (-200 4300);
FORCEPROP 2 LAST ROOM PVCCIO_CPU1
J 0
(-200 4300);
DISPLAY 1.361702 (-200 4300);
PAINT ORANGE (-200 4300);
DISPLAY INVISIBLE (-200 4300);
FORCEADD GND..1
(-250 3950);
FORCEPROP 3 LASTPIN (-250 4000) SIG_NAME GND\g
J 0
(-240 4010);
DISPLAY 0.659574 (-240 4010);
PAINT MONO (-240 4010);
DISPLAY INVISIBLE (-240 4010);
FORCEPROP 2 LAST ROOM PVCCIO_CPU1
J 0
(-825 4025);
DISPLAY 1.361702 (-825 4025);
PAINT ORANGE (-825 4025);
DISPLAY INVISIBLE (-825 4025);
FORCEPROP 1 LAST PATH I36
J 0
(-175 3950);
DISPLAY 0.872340 (-175 3950);
PAINT AQUA (-175 3950);
DISPLAY INVISIBLE (-175 3950);
FORCEPROP 1 LAST SIZE 1B
J 0
(-175 3900);
DISPLAY 1.170213 (-175 3900);
PAINT AQUA (-175 3900);
DISPLAY INVISIBLE (-175 3900);
FORCEPROP 2 LAST CDS_LIB mstr_symbols
J 0
(-250 3950);
PAINT ORANGE (-250 3950);
DISPLAY INVISIBLE (-250 3950);
FORCEPROP 1 LAST VOLTAGE 0
J 0
(-250 3950);
PAINT SKYBLUE (-250 3950);
DISPLAY INVISIBLE (-250 3950);
FORCEPROP 1 LAST BODY_TYPE PLUMBING
J 0
(-295 3907);
DISPLAY 0.340426 (-295 3907);
PAINT GREEN (-295 3907);
DISPLAY INVISIBLE (-295 3907);
FORCEPROP 1 LAST HDL_POWER GND
J 0
(-250 4100);
DISPLAY 1.170213 (-250 4100);
PAINT GREEN (-250 4100);
DISPLAY INVISIBLE (-250 4100);
FORCEADD RES..1
(-1175 2925);
FORCEPROP 1 LAST MATERIAL CHIP
J 0
(-1175 2775);
DISPLAY 0.617021 (-1175 2775);
PAINT SKYBLUE (-1175 2775);
FORCEPROP 1 LAST PACK_TYPE 0402
J 0
(-1100 2825);
DISPLAY 0.617021 (-1100 2825);
PAINT SKYBLUE (-1100 2825);
FORCEPROP 1 LAST TOLERANCE 5%
J 0
(-1225 2825);
DISPLAY 0.617021 (-1225 2825);
PAINT SKYBLUE (-1225 2825);
FORCEPROP 1 LASTPIN (-1275 2925) $PN 1
J 0
(-1263 2937);
DISPLAY 0.787234 (-1263 2937);
PAINT ORANGE (-1263 2937);
FORCEPROP 1 LASTPIN (-1075 2925) $PN 2
J 0
(-1113 2937);
DISPLAY 0.787234 (-1113 2937);
PAINT ORANGE (-1113 2937);
FORCEPROP 1 LAST LOCATION R4D54
J 0
(-1225 2975);
DISPLAY 0.617021 (-1225 2975);
PAINT AQUA (-1225 2975);
FORCEPROP 1 LAST PART_NUMBER G21497-005
J 0
(-1325 2875);
DISPLAY 0.617021 (-1325 2875);
PAINT BLUE (-1325 2875);
FORCEPROP 1 LAST WATTAGE 1/16W
J 2
(-1200 2775);
DISPLAY 0.617021 (-1200 2775);
PAINT SKYBLUE (-1200 2775);
FORCEPROP 1 LAST VALUE 0.0
J 2
(-1275 2825);
DISPLAY 0.617021 (-1275 2825);
PAINT SKYBLUE (-1275 2825);
FORCEPROP 2 LAST SEC_TYPE 0402
J 0
(-1225 3125);
DISPLAY 1.021277 (-1225 3125);
PAINT ORANGE (-1225 3125);
DISPLAY INVISIBLE (-1225 3125);
FORCEPROP 2 LAST SEC 1
J 0
(-1225 3125);
PAINT MONO (-1225 3125);
DISPLAY INVISIBLE (-1225 3125);
FORCEPROP 2 LAST CDS_LIB mstr_discrete
J 0
(-1175 2925);
PAINT ORANGE (-1175 2925);
DISPLAY INVISIBLE (-1175 2925);
FORCEPROP 2 LAST CDS_LOCATION R4D54
J 0
(-1225 2975);
DISPLAY 0.617021 (-1225 2975);
PAINT AQUA (-1225 2975);
DISPLAY INVISIBLE (-1225 2975);
FORCEPROP 2 LAST ROOM PVCCIO_CPU1
J 0
(-1225 3025);
DISPLAY 1.361702 (-1225 3025);
PAINT ORANGE (-1225 3025);
DISPLAY INVISIBLE (-1225 3025);
FORCEPROP 1 LAST PATH I37
J 0
(-1225 3075);
DISPLAY 0.978723 (-1225 3075);
PAINT WHITE (-1225 3075);
DISPLAY INVISIBLE (-1225 3075);
FORCEADD GND..1
(-850 750);
FORCEPROP 3 LASTPIN (-850 800) SIG_NAME GND\g
J 0
(-840 810);
DISPLAY 0.659574 (-840 810);
PAINT MONO (-840 810);
DISPLAY INVISIBLE (-840 810);
FORCEPROP 2 LAST ROOM PVCCIO_CPU1
J 0
(-1425 825);
DISPLAY 1.361702 (-1425 825);
PAINT ORANGE (-1425 825);
DISPLAY INVISIBLE (-1425 825);
FORCEPROP 1 LAST SIZE 1B
J 0
(-775 700);
DISPLAY 1.170213 (-775 700);
PAINT AQUA (-775 700);
DISPLAY INVISIBLE (-775 700);
FORCEPROP 1 LAST PATH I44
J 0
(-775 750);
DISPLAY 0.872340 (-775 750);
PAINT AQUA (-775 750);
DISPLAY INVISIBLE (-775 750);
FORCEPROP 2 LAST CDS_LIB mstr_symbols
J 0
(-850 750);
PAINT ORANGE (-850 750);
DISPLAY INVISIBLE (-850 750);
FORCEPROP 1 LAST VOLTAGE 0
J 0
(-850 750);
PAINT SKYBLUE (-850 750);
DISPLAY INVISIBLE (-850 750);
FORCEPROP 1 LAST BODY_TYPE PLUMBING
J 0
(-895 707);
DISPLAY 0.340426 (-895 707);
PAINT GREEN (-895 707);
DISPLAY INVISIBLE (-895 707);
FORCEPROP 1 LAST HDL_POWER GND
J 0
(-850 900);
DISPLAY 1.170213 (-850 900);
PAINT GREEN (-850 900);
DISPLAY INVISIBLE (-850 900);
FORCEADD GND..1
(-950 2025);
FORCEPROP 3 LASTPIN (-950 2075) SIG_NAME GND\g
J 0
(-940 2085);
DISPLAY 0.659574 (-940 2085);
PAINT MONO (-940 2085);
DISPLAY INVISIBLE (-940 2085);
FORCEPROP 1 LAST SIZE 1B
J 0
(-875 1975);
DISPLAY 1.170213 (-875 1975);
PAINT AQUA (-875 1975);
DISPLAY INVISIBLE (-875 1975);
FORCEPROP 1 LAST PATH I45
J 0
(-875 2025);
DISPLAY 0.872340 (-875 2025);
PAINT AQUA (-875 2025);
DISPLAY INVISIBLE (-875 2025);
FORCEPROP 2 LAST CDS_LIB mstr_symbols
J 0
(-950 2025);
PAINT ORANGE (-950 2025);
DISPLAY INVISIBLE (-950 2025);
FORCEPROP 1 LAST VOLTAGE 0
J 0
(-950 2025);
PAINT SKYBLUE (-950 2025);
DISPLAY INVISIBLE (-950 2025);
FORCEPROP 2 LAST ROOM PVCCIO_CPU1
J 0
(-1525 2100);
DISPLAY 1.361702 (-1525 2100);
PAINT ORANGE (-1525 2100);
DISPLAY INVISIBLE (-1525 2100);
FORCEPROP 1 LAST BODY_TYPE PLUMBING
J 0
(-995 1982);
DISPLAY 0.340426 (-995 1982);
PAINT GREEN (-995 1982);
DISPLAY INVISIBLE (-995 1982);
FORCEPROP 1 LAST HDL_POWER GND
J 0
(-950 2175);
DISPLAY 1.170213 (-950 2175);
PAINT GREEN (-950 2175);
DISPLAY INVISIBLE (-950 2175);
FORCEADD RES..1
(-1825 3925);
FORCEPROP 1 LAST LOCATION R4D51
J 0
(-1925 4100);
DISPLAY 0.617021 (-1925 4100);
PAINT AQUA (-1925 4100);
FORCEPROP 1 LASTPIN (-1925 3925) $PN 1
J 0
(-1913 3937);
DISPLAY 0.617021 (-1913 3937);
PAINT ORANGE (-1913 3937);
FORCEPROP 1 LAST WATTAGE 1/16W
J 2
(-1775 3950);
DISPLAY 0.617021 (-1775 3950);
PAINT SKYBLUE (-1775 3950);
FORCEPROP 1 LASTPIN (-1725 3925) $PN 2
J 0
(-1763 3937);
DISPLAY 0.617021 (-1763 3937);
PAINT ORANGE (-1763 3937);
FORCEPROP 1 LAST VALUE 150.0
J 2
(-1825 4000);
DISPLAY 0.617021 (-1825 4000);
PAINT SKYBLUE (-1825 4000);
FORCEPROP 1 LAST PACK_TYPE 0402
J 0
(-1650 4000);
DISPLAY 0.617021 (-1650 4000);
PAINT SKYBLUE (-1650 4000);
FORCEPROP 1 LAST MATERIAL CHIP
J 0
(-1725 3950);
DISPLAY 0.617021 (-1725 3950);
PAINT SKYBLUE (-1725 3950);
FORCEPROP 1 LAST TOLERANCE 1%
J 0
(-1775 4000);
DISPLAY 0.617021 (-1775 4000);
PAINT SKYBLUE (-1775 4000);
FORCEPROP 1 LAST PART_NUMBER G21796-009
J 0
(-1925 4050);
DISPLAY 0.617021 (-1925 4050);
PAINT BLUE (-1925 4050);
FORCEPROP 2 LAST CDS_LIB mstr_discrete
J 0
(-1825 3925);
PAINT ORANGE (-1825 3925);
DISPLAY INVISIBLE (-1825 3925);
FORCEPROP 1 LAST PATH I46
J 0
(-1875 4075);
DISPLAY 0.978723 (-1875 4075);
PAINT WHITE (-1875 4075);
DISPLAY INVISIBLE (-1875 4075);
FORCEPROP 2 LAST ROOM PVCCIO_CPU1
J 0
(-1925 4150);
DISPLAY 1.361702 (-1925 4150);
PAINT ORANGE (-1925 4150);
DISPLAY INVISIBLE (-1925 4150);
FORCEPROP 2 LAST CDS_LOCATION R4D51
J 0
(-1925 4100);
DISPLAY 0.617021 (-1925 4100);
PAINT AQUA (-1925 4100);
DISPLAY INVISIBLE (-1925 4100);
FORCEPROP 2 LAST SEC 1
J 0
(-1875 4150);
DISPLAY 0.680851 (-1875 4150);
PAINT MONO (-1875 4150);
DISPLAY INVISIBLE (-1875 4150);
FORCEPROP 2 LAST SEC_TYPE 0402
J 0
(-1875 4150);
DISPLAY 1.021277 (-1875 4150);
PAINT ORANGE (-1875 4150);
DISPLAY INVISIBLE (-1875 4150);
FORCEADD GND..1
(-2425 4000);
FORCEPROP 3 LASTPIN (-2425 4050) SIG_NAME GND\g
J 0
(-2415 4060);
DISPLAY 0.659574 (-2415 4060);
PAINT MONO (-2415 4060);
DISPLAY INVISIBLE (-2415 4060);
FORCEPROP 1 LAST PATH I47
J 0
(-2350 4000);
DISPLAY 0.872340 (-2350 4000);
PAINT AQUA (-2350 4000);
DISPLAY INVISIBLE (-2350 4000);
FORCEPROP 1 LAST SIZE 1B
J 0
(-2350 3950);
DISPLAY 1.170213 (-2350 3950);
PAINT AQUA (-2350 3950);
DISPLAY INVISIBLE (-2350 3950);
FORCEPROP 2 LAST CDS_LIB mstr_symbols
J 0
(-2425 4000);
PAINT ORANGE (-2425 4000);
DISPLAY INVISIBLE (-2425 4000);
FORCEPROP 1 LAST VOLTAGE 0
J 0
(-2425 4000);
PAINT SKYBLUE (-2425 4000);
DISPLAY INVISIBLE (-2425 4000);
FORCEPROP 2 LAST ROOM PVCCIO_CPU1
J 0
(-3000 4075);
DISPLAY 1.361702 (-3000 4075);
PAINT ORANGE (-3000 4075);
DISPLAY INVISIBLE (-3000 4075);
FORCEPROP 1 LAST BODY_TYPE PLUMBING
J 0
(-2470 3957);
DISPLAY 0.340426 (-2470 3957);
PAINT GREEN (-2470 3957);
DISPLAY INVISIBLE (-2470 3957);
FORCEPROP 1 LAST HDL_POWER GND
J 0
(-2425 4150);
DISPLAY 1.170213 (-2425 4150);
PAINT GREEN (-2425 4150);
DISPLAY INVISIBLE (-2425 4150);
FORCEADD GND..1
(-2850 4025);
FORCEPROP 3 LASTPIN (-2850 4075) SIG_NAME GND\g
J 0
(-2840 4085);
DISPLAY 0.659574 (-2840 4085);
PAINT MONO (-2840 4085);
DISPLAY INVISIBLE (-2840 4085);
FORCEPROP 1 LAST PATH I49
J 0
(-2775 4025);
DISPLAY 0.872340 (-2775 4025);
PAINT AQUA (-2775 4025);
DISPLAY INVISIBLE (-2775 4025);
FORCEPROP 2 LAST CDS_LIB mstr_symbols
J 0
(-2850 4025);
PAINT ORANGE (-2850 4025);
DISPLAY INVISIBLE (-2850 4025);
FORCEPROP 1 LAST SIZE 1B
J 0
(-2775 3975);
DISPLAY 1.170213 (-2775 3975);
PAINT AQUA (-2775 3975);
DISPLAY INVISIBLE (-2775 3975);
FORCEPROP 1 LAST VOLTAGE 0
J 0
(-2850 4025);
PAINT SKYBLUE (-2850 4025);
DISPLAY INVISIBLE (-2850 4025);
FORCEPROP 2 LAST ROOM PVCCIO_CPU1
J 0
(-3425 4100);
DISPLAY 1.361702 (-3425 4100);
PAINT ORANGE (-3425 4100);
DISPLAY INVISIBLE (-3425 4100);
FORCEPROP 1 LAST BODY_TYPE PLUMBING
J 0
(-2895 3982);
DISPLAY 0.340426 (-2895 3982);
PAINT GREEN (-2895 3982);
DISPLAY INVISIBLE (-2895 3982);
FORCEPROP 1 LAST HDL_POWER GND
J 0
(-2850 4175);
DISPLAY 1.170213 (-2850 4175);
PAINT GREEN (-2850 4175);
DISPLAY INVISIBLE (-2850 4175);
FORCEADD OFFPAGE..2
(2775 2975);
FORCEPROP 2 LAST $XR0 214 
J 0
(2964 2975);
DISPLAY 0.638298 (2964 2975);
PAINT MONO (2964 2975);
FORCEPROP 2 LAST CDS_LIB mstr_standard
J 0
(2775 2975);
PAINT ORANGE (2775 2975);
DISPLAY INVISIBLE (2775 2975);
FORCEPROP 2 LAST PATH I5
J 0
(2950 3050);
DISPLAY 1.021277 (2950 3050);
PAINT ORANGE (2950 3050);
DISPLAY INVISIBLE (2950 3050);
FORCEPROP 2 LAST ROOM PVCCIO_CPU1
J 0
(2350 3050);
DISPLAY 1.361702 (2350 3050);
PAINT ORANGE (2350 3050);
DISPLAY INVISIBLE (2350 3050);
FORCEPROP 1 LAST OFFPAGE TRUE
J 0
(3100 2850);
DISPLAY 1.170213 (3100 2850);
PAINT GREEN (3100 2850);
DISPLAY INVISIBLE (3100 2850);
FORCEPROP 1 LAST COMMENT_BODY TRUE
J 0
(2730 2880);
DISPLAY 1.170213 (2730 2880);
PAINT GREEN (2730 2880);
DISPLAY INVISIBLE (2730 2880);
FORCEADD OFFPAGE..1
(-2875 3925);
FORCEPROP 2 LAST $XR2 206 
J 0
(-3336 3925);
DISPLAY 0.638298 (-3336 3925);
PAINT MONO (-3336 3925);
FORCEPROP 2 LAST $XR1 193 
J 0
(-3216 3925);
DISPLAY 0.638298 (-3216 3925);
PAINT MONO (-3216 3925);
FORCEPROP 2 LAST $XR0 55 
J 0
(-3096 3925);
DISPLAY 0.638298 (-3096 3925);
PAINT MONO (-3096 3925);
FORCEPROP 2 LAST ROOM PVCCIO_CPU1
J 0
(-3425 4000);
DISPLAY 1.361702 (-3425 4000);
PAINT ORANGE (-3425 4000);
DISPLAY INVISIBLE (-3425 4000);
FORCEPROP 2 LAST PATH I50
J 0
(-2825 4000);
DISPLAY 1.021277 (-2825 4000);
PAINT ORANGE (-2825 4000);
DISPLAY INVISIBLE (-2825 4000);
FORCEPROP 2 LAST CDS_LIB mstr_standard
J 0
(-2875 3925);
PAINT ORANGE (-2875 3925);
DISPLAY INVISIBLE (-2875 3925);
FORCEPROP 1 LAST OFFPAGE TRUE
J 0
(-2550 3800);
DISPLAY 1.170213 (-2550 3800);
PAINT GREEN (-2550 3800);
DISPLAY INVISIBLE (-2550 3800);
FORCEPROP 1 LAST COMMENT_BODY TRUE
J 0
(-2750 3825);
DISPLAY 1.170213 (-2750 3825);
PAINT GREEN (-2750 3825);
DISPLAY INVISIBLE (-2750 3825);
FORCEADD OFFPAGE..1
(-2675 3375);
FORCEPROP 2 LAST $XR0 214 
J 0
(-2927 3375);
DISPLAY 0.638298 (-2927 3375);
PAINT MONO (-2927 3375);
FORCEPROP 2 LAST ROOM PVCCIO_CPU1
J 0
(-3225 3450);
DISPLAY 1.361702 (-3225 3450);
PAINT ORANGE (-3225 3450);
DISPLAY INVISIBLE (-3225 3450);
FORCEPROP 2 LAST PATH I51
J 0
(-2625 3450);
DISPLAY 1.021277 (-2625 3450);
PAINT ORANGE (-2625 3450);
DISPLAY INVISIBLE (-2625 3450);
FORCEPROP 2 LAST CDS_LIB mstr_standard
J 0
(-2675 3375);
PAINT ORANGE (-2675 3375);
DISPLAY INVISIBLE (-2675 3375);
FORCEPROP 1 LAST OFFPAGE TRUE
J 0
(-2350 3250);
DISPLAY 1.170213 (-2350 3250);
PAINT GREEN (-2350 3250);
DISPLAY INVISIBLE (-2350 3250);
FORCEPROP 1 LAST COMMENT_BODY TRUE
J 0
(-2550 3275);
DISPLAY 1.170213 (-2550 3275);
PAINT GREEN (-2550 3275);
DISPLAY INVISIBLE (-2550 3275);
FORCEADD OFFPAGE..1
(-2675 3425);
FORCEPROP 2 LAST $XR0 214 
J 0
(-2927 3425);
DISPLAY 0.638298 (-2927 3425);
PAINT MONO (-2927 3425);
FORCEPROP 2 LAST ROOM PVCCIO_CPU1
J 0
(-3225 3500);
DISPLAY 1.361702 (-3225 3500);
PAINT ORANGE (-3225 3500);
DISPLAY INVISIBLE (-3225 3500);
FORCEPROP 2 LAST PATH I52
J 0
(-2625 3500);
DISPLAY 1.021277 (-2625 3500);
PAINT ORANGE (-2625 3500);
DISPLAY INVISIBLE (-2625 3500);
FORCEPROP 2 LAST CDS_LIB mstr_standard
J 0
(-2675 3425);
PAINT ORANGE (-2675 3425);
DISPLAY INVISIBLE (-2675 3425);
FORCEPROP 1 LAST OFFPAGE TRUE
J 0
(-2350 3300);
DISPLAY 1.170213 (-2350 3300);
PAINT GREEN (-2350 3300);
DISPLAY INVISIBLE (-2350 3300);
FORCEPROP 1 LAST COMMENT_BODY TRUE
J 0
(-2550 3325);
DISPLAY 1.170213 (-2550 3325);
PAINT GREEN (-2550 3325);
DISPLAY INVISIBLE (-2550 3325);
FORCEADD OFFPAGE..1
(-2675 3125);
FORCEPROP 2 LAST $XR0 213 
J 0
(-2927 3125);
DISPLAY 0.638298 (-2927 3125);
PAINT MONO (-2927 3125);
FORCEPROP 2 LAST ROOM PVCCIO_CPU1
J 0
(-3225 3200);
DISPLAY 1.361702 (-3225 3200);
PAINT ORANGE (-3225 3200);
DISPLAY INVISIBLE (-3225 3200);
FORCEPROP 2 LAST PATH I53
J 0
(-2625 3200);
DISPLAY 1.021277 (-2625 3200);
PAINT ORANGE (-2625 3200);
DISPLAY INVISIBLE (-2625 3200);
FORCEPROP 2 LAST CDS_LIB mstr_standard
J 0
(-2675 3125);
PAINT ORANGE (-2675 3125);
DISPLAY INVISIBLE (-2675 3125);
FORCEPROP 1 LAST OFFPAGE TRUE
J 0
(-2350 3000);
DISPLAY 1.170213 (-2350 3000);
PAINT GREEN (-2350 3000);
DISPLAY INVISIBLE (-2350 3000);
FORCEPROP 1 LAST COMMENT_BODY TRUE
J 0
(-2550 3025);
DISPLAY 1.170213 (-2550 3025);
PAINT GREEN (-2550 3025);
DISPLAY INVISIBLE (-2550 3025);
FORCEADD OFFPAGE..1
(-2675 3225);
FORCEPROP 2 LAST $XR0 190 
J 0
(-2927 3225);
DISPLAY 0.638298 (-2927 3225);
PAINT MONO (-2927 3225);
FORCEPROP 2 LAST ROOM PVCCIO_CPU1
J 0
(-3225 3300);
DISPLAY 1.361702 (-3225 3300);
PAINT ORANGE (-3225 3300);
DISPLAY INVISIBLE (-3225 3300);
FORCEPROP 2 LAST CDS_LIB mstr_standard
J 0
(-2675 3225);
PAINT ORANGE (-2675 3225);
DISPLAY INVISIBLE (-2675 3225);
FORCEPROP 2 LAST PATH I54
J 0
(-2625 3300);
DISPLAY 1.021277 (-2625 3300);
PAINT ORANGE (-2625 3300);
DISPLAY INVISIBLE (-2625 3300);
FORCEPROP 1 LAST OFFPAGE TRUE
J 0
(-2350 3100);
DISPLAY 1.170213 (-2350 3100);
PAINT GREEN (-2350 3100);
DISPLAY INVISIBLE (-2350 3100);
FORCEPROP 1 LAST COMMENT_BODY TRUE
J 0
(-2550 3125);
DISPLAY 1.170213 (-2550 3125);
PAINT GREEN (-2550 3125);
DISPLAY INVISIBLE (-2550 3125);
FORCEADD OFFPAGE..1
(-2675 3275);
FORCEPROP 2 LAST $XR0 214 
J 0
(-2927 3275);
DISPLAY 0.638298 (-2927 3275);
PAINT MONO (-2927 3275);
FORCEPROP 2 LAST ROOM PVCCIO_CPU1
J 0
(-3225 3350);
DISPLAY 1.361702 (-3225 3350);
PAINT ORANGE (-3225 3350);
DISPLAY INVISIBLE (-3225 3350);
FORCEPROP 2 LAST CDS_LIB mstr_standard
J 0
(-2675 3275);
PAINT ORANGE (-2675 3275);
DISPLAY INVISIBLE (-2675 3275);
FORCEPROP 2 LAST PATH I55
J 0
(-2625 3350);
DISPLAY 1.021277 (-2625 3350);
PAINT ORANGE (-2625 3350);
DISPLAY INVISIBLE (-2625 3350);
FORCEPROP 1 LAST OFFPAGE TRUE
J 0
(-2350 3150);
DISPLAY 1.170213 (-2350 3150);
PAINT GREEN (-2350 3150);
DISPLAY INVISIBLE (-2350 3150);
FORCEPROP 1 LAST COMMENT_BODY TRUE
J 0
(-2550 3175);
DISPLAY 1.170213 (-2550 3175);
PAINT GREEN (-2550 3175);
DISPLAY INVISIBLE (-2550 3175);
FORCEADD OFFPAGE..2
R 2
(-2675 2925);
FORCEPROP 2 LAST $XR2 206 
J 0
(-3139 2925);
DISPLAY 0.638298 (-3139 2925);
PAINT MONO (-3139 2925);
FORCEPROP 2 LAST $XR1 193 
J 0
(-3019 2925);
DISPLAY 0.638298 (-3019 2925);
PAINT MONO (-3019 2925);
FORCEPROP 2 LAST $XR0 55 
J 0
(-2899 2925);
DISPLAY 0.638298 (-2899 2925);
PAINT MONO (-2899 2925);
FORCEPROP 2 LAST ROOM PVCCIO_CPU1
J 0
(-3225 3000);
DISPLAY 1.361702 (-3225 3000);
PAINT ORANGE (-3225 3000);
DISPLAY INVISIBLE (-3225 3000);
FORCEPROP 2 LAST CDS_LIB mstr_standard
J 0
(-2675 2925);
PAINT ORANGE (-2675 2925);
DISPLAY INVISIBLE (-2675 2925);
FORCEPROP 2 LAST PATH I57
J 0
(-2625 3000);
DISPLAY 1.021277 (-2625 3000);
PAINT ORANGE (-2625 3000);
DISPLAY INVISIBLE (-2625 3000);
FORCEPROP 1 LAST OFFPAGE TRUE
J 2
(-3000 2800);
DISPLAY 1.170213 (-3000 2800);
PAINT GREEN (-3000 2800);
DISPLAY INVISIBLE (-3000 2800);
FORCEPROP 1 LAST COMMENT_BODY TRUE
J 2
(-2630 2830);
DISPLAY 1.170213 (-2630 2830);
PAINT GREEN (-2630 2830);
DISPLAY INVISIBLE (-2630 2830);
FORCEADD OFFPAGE..2
R 2
(-2675 2975);
FORCEPROP 2 LAST $XR0 213 
J 0
(-2930 2975);
DISPLAY 0.638298 (-2930 2975);
PAINT MONO (-2930 2975);
FORCEPROP 2 LAST ROOM PVCCIO_CPU1
J 0
(-3225 3050);
DISPLAY 1.361702 (-3225 3050);
PAINT ORANGE (-3225 3050);
DISPLAY INVISIBLE (-3225 3050);
FORCEPROP 2 LAST CDS_LIB mstr_standard
J 0
(-2675 2975);
PAINT ORANGE (-2675 2975);
DISPLAY INVISIBLE (-2675 2975);
FORCEPROP 2 LAST PATH I58
J 0
(-2625 3050);
DISPLAY 1.021277 (-2625 3050);
PAINT ORANGE (-2625 3050);
DISPLAY INVISIBLE (-2625 3050);
FORCEPROP 1 LAST OFFPAGE TRUE
J 2
(-3000 2850);
DISPLAY 1.170213 (-3000 2850);
PAINT GREEN (-3000 2850);
DISPLAY INVISIBLE (-3000 2850);
FORCEPROP 1 LAST COMMENT_BODY TRUE
J 2
(-2630 2880);
DISPLAY 1.170213 (-2630 2880);
PAINT GREEN (-2630 2880);
DISPLAY INVISIBLE (-2630 2880);
FORCEADD OFFPAGE..2
R 2
(-2675 2375);
FORCEPROP 2 LAST ROOM PVCCIO_CPU1
J 0
(-3225 2450);
DISPLAY 1.361702 (-3225 2450);
PAINT ORANGE (-3225 2450);
DISPLAY INVISIBLE (-3225 2450);
FORCEPROP 2 LAST CDS_LIB mstr_standard
J 0
(-2675 2375);
PAINT ORANGE (-2675 2375);
DISPLAY INVISIBLE (-2675 2375);
FORCEPROP 2 LAST PATH I61
J 0
(-2625 2450);
DISPLAY 1.021277 (-2625 2450);
PAINT ORANGE (-2625 2450);
DISPLAY INVISIBLE (-2625 2450);
FORCEPROP 1 LAST OFFPAGE TRUE
J 2
(-3000 2250);
DISPLAY 1.170213 (-3000 2250);
PAINT GREEN (-3000 2250);
DISPLAY INVISIBLE (-3000 2250);
FORCEPROP 1 LAST COMMENT_BODY TRUE
J 2
(-2630 2280);
DISPLAY 1.170213 (-2630 2280);
PAINT GREEN (-2630 2280);
DISPLAY INVISIBLE (-2630 2280);
FORCEPROP 2 LAST $XR11 226 
J 0
(-3104 2375);
DISPLAY 0.638298 (-3104 2375);
PAINT MONO (-3104 2375);
DISPLAY INVISIBLE (-3104 2375);
FORCEPROP 2 LAST $XR10 223 
J 0
(-3104 2375);
DISPLAY 0.638298 (-3104 2375);
PAINT MONO (-3104 2375);
DISPLAY INVISIBLE (-3104 2375);
FORCEPROP 2 LAST $XR9 218 
J 0
(-3104 2375);
DISPLAY 0.638298 (-3104 2375);
PAINT MONO (-3104 2375);
DISPLAY INVISIBLE (-3104 2375);
FORCEPROP 2 LAST $XR8 215 
J 0
(-3104 2375);
DISPLAY 0.638298 (-3104 2375);
PAINT MONO (-3104 2375);
DISPLAY INVISIBLE (-3104 2375);
FORCEPROP 2 LAST $XR7 206 
J 0
(-3104 2375);
DISPLAY 0.638298 (-3104 2375);
PAINT MONO (-3104 2375);
DISPLAY INVISIBLE (-3104 2375);
FORCEPROP 2 LAST $XR6 201 
J 0
(-3104 2375);
DISPLAY 0.638298 (-3104 2375);
PAINT MONO (-3104 2375);
DISPLAY INVISIBLE (-3104 2375);
FORCEPROP 2 LAST $XR5 194 
J 0
(-3104 2375);
DISPLAY 0.638298 (-3104 2375);
PAINT MONO (-3104 2375);
DISPLAY INVISIBLE (-3104 2375);
FORCEPROP 2 LAST $XR4 193 
J 0
(-3104 2375);
DISPLAY 0.638298 (-3104 2375);
PAINT MONO (-3104 2375);
DISPLAY INVISIBLE (-3104 2375);
FORCEPROP 2 LAST $XR3 235 
J 0
(-3104 2375);
DISPLAY 0.638298 (-3104 2375);
PAINT MONO (-3104 2375);
DISPLAY INVISIBLE (-3104 2375);
FORCEPROP 2 LAST $XR2 211 
J 0
(-3104 2375);
DISPLAY 0.638298 (-3104 2375);
PAINT MONO (-3104 2375);
DISPLAY INVISIBLE (-3104 2375);
FORCEPROP 2 LAST $XR1 159 
J 0
(-3104 2375);
DISPLAY 0.638298 (-3104 2375);
PAINT MONO (-3104 2375);
DISPLAY INVISIBLE (-3104 2375);
FORCEPROP 2 LAST $XR0 138 
J 0
(-3104 2375);
DISPLAY 0.638298 (-3104 2375);
PAINT MONO (-3104 2375);
DISPLAY INVISIBLE (-3104 2375);
FORCEADD OFFPAGE..3
R 2
(-2675 2425);
FORCEPROP 2 LAST $XR11 235 
J 0
(-3435 2389);
DISPLAY 0.638298 (-3435 2389);
PAINT MONO (-3435 2389);
FORCEPROP 2 LAST $XR10 226 
J 0
(-3315 2389);
DISPLAY 0.638298 (-3315 2389);
PAINT MONO (-3315 2389);
FORCEPROP 2 LAST $XR9 223 
J 0
(-3195 2389);
DISPLAY 0.638298 (-3195 2389);
PAINT MONO (-3195 2389);
FORCEPROP 2 LAST $XR8 218 
J 0
(-3075 2389);
DISPLAY 0.638298 (-3075 2389);
PAINT MONO (-3075 2389);
FORCEPROP 2 LAST $XR7 215 
J 0
(-2955 2389);
DISPLAY 0.638298 (-2955 2389);
PAINT MONO (-2955 2389);
FORCEPROP 2 LAST $XR6 211 
J 0
(-3675 2425);
DISPLAY 0.638298 (-3675 2425);
PAINT MONO (-3675 2425);
FORCEPROP 2 LAST $XR5 206 
J 0
(-3555 2425);
DISPLAY 0.638298 (-3555 2425);
PAINT MONO (-3555 2425);
FORCEPROP 2 LAST $XR4 201 
J 0
(-3435 2425);
DISPLAY 0.638298 (-3435 2425);
PAINT MONO (-3435 2425);
FORCEPROP 2 LAST $XR3 194 
J 0
(-3315 2425);
DISPLAY 0.638298 (-3315 2425);
PAINT MONO (-3315 2425);
FORCEPROP 2 LAST $XR2 193 
J 0
(-3195 2425);
DISPLAY 0.638298 (-3195 2425);
PAINT MONO (-3195 2425);
FORCEPROP 2 LAST $XR1 159 
J 0
(-3075 2425);
DISPLAY 0.638298 (-3075 2425);
PAINT MONO (-3075 2425);
FORCEPROP 2 LAST $XR0 138 
J 0
(-2955 2425);
DISPLAY 0.638298 (-2955 2425);
PAINT MONO (-2955 2425);
FORCEPROP 2 LAST ROOM PVCCIO_CPU1
J 0
(-3225 2500);
DISPLAY 1.361702 (-3225 2500);
PAINT ORANGE (-3225 2500);
DISPLAY INVISIBLE (-3225 2500);
FORCEPROP 2 LAST CDS_LIB mstr_standard
J 0
(-2675 2425);
PAINT ORANGE (-2675 2425);
DISPLAY INVISIBLE (-2675 2425);
FORCEPROP 2 LAST PATH I62
J 0
(-2625 2500);
DISPLAY 1.021277 (-2625 2500);
PAINT ORANGE (-2625 2500);
DISPLAY INVISIBLE (-2625 2500);
FORCEPROP 1 LAST OFFPAGE TRUE
J 2
(-3000 2300);
DISPLAY 0.872340 (-3000 2300);
PAINT GREEN (-3000 2300);
DISPLAY INVISIBLE (-3000 2300);
FORCEPROP 1 LAST COMMENT_BODY TRUE
J 2
(-2625 2325);
DISPLAY 0.872340 (-2625 2325);
PAINT GREEN (-2625 2325);
DISPLAY INVISIBLE (-2625 2325);
FORCEADD RES..2
(2175 4050);
FORCEPROP 1 LAST PART_NUMBER G21796-026
J 0
(2215 3925);
DISPLAY 0.617021 (2215 3925);
PAINT BLUE (2215 3925);
FORCEPROP 1 LAST WATTAGE 1/16W
J 0
(2215 4025);
DISPLAY 0.617021 (2215 4025);
PAINT SKYBLUE (2215 4025);
FORCEPROP 1 LAST MATERIAL CHIP
J 0
(2215 3975);
DISPLAY 0.617021 (2215 3975);
PAINT SKYBLUE (2215 3975);
FORCEPROP 1 LAST TOLERANCE 1%
J 0
(2220 4075);
DISPLAY 0.617021 (2220 4075);
PAINT SKYBLUE (2220 4075);
FORCEPROP 1 LAST VALUE 1.00K
J 0
(2220 4125);
DISPLAY 0.617021 (2220 4125);
PAINT SKYBLUE (2220 4125);
FORCEPROP 1 LAST PACK_TYPE 0402
J 0
(2215 3875);
DISPLAY 0.617021 (2215 3875);
PAINT SKYBLUE (2215 3875);
FORCEPROP 1 LASTPIN (2175 3950) $PN 2
J 0
(2180 3960);
DISPLAY 0.787234 (2180 3960);
PAINT ORANGE (2180 3960);
FORCEPROP 1 LASTPIN (2175 4150) $PN 1
J 0
(2180 4112);
DISPLAY 0.787234 (2180 4112);
PAINT ORANGE (2180 4112);
FORCEPROP 1 LAST LOCATION R4D49
J 0
(2220 4175);
DISPLAY 0.617021 (2220 4175);
PAINT AQUA (2220 4175);
FORCEPROP 2 LAST SEC_TYPE 0402
J 0
(2225 4275);
DISPLAY 1.021277 (2225 4275);
PAINT ORANGE (2225 4275);
DISPLAY INVISIBLE (2225 4275);
FORCEPROP 2 LAST SEC 1
J 0
(2225 4275);
DISPLAY 0.680851 (2225 4275);
PAINT MONO (2225 4275);
DISPLAY INVISIBLE (2225 4275);
FORCEPROP 2 LAST CDS_LIB mstr_discrete
J 0
(2175 4050);
PAINT ORANGE (2175 4050);
DISPLAY INVISIBLE (2175 4050);
FORCEPROP 1 LAST PATH I63
J 0
(2225 4225);
DISPLAY 0.978723 (2225 4225);
PAINT WHITE (2225 4225);
DISPLAY INVISIBLE (2225 4225);
FORCEPROP 2 LAST CDS_LOCATION R4D49
J 0
(2220 4175);
DISPLAY 0.617021 (2220 4175);
PAINT AQUA (2220 4175);
DISPLAY INVISIBLE (2220 4175);
FORCEADD CAP..1
(1750 2700);
FORCEPROP 1 LAST PART_NUMBER A36096-046
J 0
(1800 2550);
DISPLAY 0.617021 (1800 2550);
PAINT BLUE (1800 2550);
FORCEPROP 1 LAST VALUE 1000PF
J 0
(1800 2750);
DISPLAY 0.617021 (1800 2750);
PAINT SKYBLUE (1800 2750);
FORCEPROP 1 LASTPIN (1750 2600) $PN 2
J 0
(1760 2580);
DISPLAY 0.617021 (1760 2580);
PAINT ORANGE (1760 2580);
FORCEPROP 1 LAST VOLTAGE 50V
J 0
(1800 2700);
DISPLAY 0.617021 (1800 2700);
PAINT SKYBLUE (1800 2700);
FORCEPROP 1 LASTPIN (1750 2800) $PN 1
J 0
(1760 2780);
DISPLAY 0.617021 (1760 2780);
PAINT ORANGE (1760 2780);
FORCEPROP 1 LAST PACK_TYPE 0402LF
J 0
(1825 2500);
DISPLAY 0.617021 (1825 2500);
PAINT SKYBLUE (1825 2500);
FORCEPROP 1 LAST LOCATION C4D33
J 0
(1800 2800);
DISPLAY 0.617021 (1800 2800);
PAINT AQUA (1800 2800);
FORCEPROP 1 LAST TOLERANCE 10%
J 0
(1800 2650);
DISPLAY 0.617021 (1800 2650);
PAINT SKYBLUE (1800 2650);
FORCEPROP 1 LAST MATERIAL X7R
J 0
(1800 2600);
DISPLAY 0.617021 (1800 2600);
PAINT SKYBLUE (1800 2600);
FORCEPROP 2 LAST CDS_LIB mstr_discrete
J 0
(1750 2700);
PAINT MONO (1750 2700);
DISPLAY INVISIBLE (1750 2700);
FORCEPROP 2 LAST SEC_TYPE 0402LF
J 0
(1800 2900);
DISPLAY 1.021277 (1800 2900);
PAINT ORANGE (1800 2900);
DISPLAY INVISIBLE (1800 2900);
FORCEPROP 2 LAST SEC 1
J 0
(1800 2900);
DISPLAY 0.680851 (1800 2900);
PAINT MONO (1800 2900);
DISPLAY INVISIBLE (1800 2900);
FORCEPROP 2 LAST CDS_LOCATION C4D33
J 0
(1800 2800);
DISPLAY 0.617021 (1800 2800);
PAINT AQUA (1800 2800);
DISPLAY INVISIBLE (1800 2800);
FORCEPROP 1 LAST PATH I73
J 0
(1800 2850);
DISPLAY 0.978723 (1800 2850);
PAINT WHITE (1800 2850);
DISPLAY INVISIBLE (1800 2850);
FORCEPROP 0 LAST ROOM PVCCIO_CPU1_VR
J 0
(1800 2900);
DISPLAY 1.021277 (1800 2900);
PAINT ORANGE (1800 2900);
DISPLAY INVISIBLE (1800 2900);
FORCEADD GND..1
(1750 2500);
FORCEPROP 3 LASTPIN (1750 2550) SIG_NAME GND\g
J 0
(1760 2560);
DISPLAY 0.659574 (1760 2560);
PAINT MONO (1760 2560);
DISPLAY INVISIBLE (1760 2560);
FORCEPROP 2 LAST ROOM PVCCIO_CPU1
J 0
(1175 2575);
DISPLAY 1.361702 (1175 2575);
PAINT ORANGE (1175 2575);
DISPLAY INVISIBLE (1175 2575);
FORCEPROP 1 LAST PATH I74
J 0
(1825 2500);
DISPLAY 0.872340 (1825 2500);
PAINT AQUA (1825 2500);
DISPLAY INVISIBLE (1825 2500);
FORCEPROP 1 LAST SIZE 1B
J 0
(1825 2450);
DISPLAY 1.170213 (1825 2450);
PAINT AQUA (1825 2450);
DISPLAY INVISIBLE (1825 2450);
FORCEPROP 2 LAST CDS_LIB mstr_symbols
J 0
(1750 2500);
PAINT MONO (1750 2500);
DISPLAY INVISIBLE (1750 2500);
FORCEPROP 1 LAST VOLTAGE 0
J 0
(1750 2500);
PAINT SKYBLUE (1750 2500);
DISPLAY INVISIBLE (1750 2500);
FORCEPROP 1 LAST BODY_TYPE PLUMBING
J 0
(1705 2457);
DISPLAY 0.340426 (1705 2457);
PAINT GREEN (1705 2457);
DISPLAY INVISIBLE (1705 2457);
FORCEPROP 1 LAST HDL_POWER GND
J 0
(1750 2650);
DISPLAY 1.170213 (1750 2650);
PAINT GREEN (1750 2650);
DISPLAY INVISIBLE (1750 2650);
FORCEADD OFFPAGE..1
R 2
(2800 1750);
FORCEPROP 2 LAST $XR0 213 
J 0
(2986 1750);
DISPLAY 0.638298 (2986 1750);
PAINT MONO (2986 1750);
FORCEPROP 2 LAST ROOM PVCCIO_CPU1
J 0
(2375 1825);
DISPLAY 1.361702 (2375 1825);
PAINT ORANGE (2375 1825);
DISPLAY INVISIBLE (2375 1825);
FORCEPROP 2 LAST CDS_LIB mstr_standard
J 2
(2800 1750);
PAINT ORANGE (2800 1750);
DISPLAY INVISIBLE (2800 1750);
FORCEPROP 2 LAST PATH I8
J 0
(2975 1825);
DISPLAY 1.021277 (2975 1825);
PAINT ORANGE (2975 1825);
DISPLAY INVISIBLE (2975 1825);
FORCEPROP 1 LAST OFFPAGE TRUE
J 2
(2475 1625);
DISPLAY 1.170213 (2475 1625);
PAINT GREEN (2475 1625);
DISPLAY INVISIBLE (2475 1625);
FORCEPROP 1 LAST COMMENT_BODY TRUE
J 2
(2675 1650);
DISPLAY 1.170213 (2675 1650);
PAINT GREEN (2675 1650);
DISPLAY INVISIBLE (2675 1650);
FORCEADD CAP..1
(-2075 1725);
FORCEPROP 1 LAST PART_NUMBER A36096-050
J 0
(-2025 1675);
DISPLAY 0.617021 (-2025 1675);
PAINT BLUE (-2025 1675);
FORCEPROP 1 LAST PACK_TYPE 0402LF
J 0
(-2025 1625);
DISPLAY 0.617021 (-2025 1625);
PAINT SKYBLUE (-2025 1625);
FORCEPROP 1 LAST VOLTAGE 50V
J 0
(-2025 1725);
DISPLAY 0.617021 (-2025 1725);
PAINT SKYBLUE (-2025 1725);
FORCEPROP 1 LAST VALUE 220PF
J 0
(-2025 1775);
DISPLAY 0.617021 (-2025 1775);
PAINT SKYBLUE (-2025 1775);
FORCEPROP 1 LAST TOLERANCE 10%
J 0
(-1850 1775);
DISPLAY 0.617021 (-1850 1775);
PAINT SKYBLUE (-1850 1775);
FORCEPROP 1 LASTPIN (-2075 1825) $PN 1
J 0
(-2065 1805);
DISPLAY 0.617021 (-2065 1805);
PAINT ORANGE (-2065 1805);
FORCEPROP 1 LASTPIN (-2075 1625) $PN 2
J 0
(-2065 1605);
DISPLAY 0.617021 (-2065 1605);
PAINT ORANGE (-2065 1605);
FORCEPROP 1 LAST LOCATION C4D44
J 0
(-2025 1825);
DISPLAY 0.617021 (-2025 1825);
PAINT AQUA (-2025 1825);
FORCEPROP 1 LAST MATERIAL X7R
J 0
(-1900 1725);
DISPLAY 0.617021 (-1900 1725);
PAINT SKYBLUE (-1900 1725);
FORCEPROP 2 LAST CDS_LIB mstr_discrete
J 0
(-2075 1725);
PAINT ORANGE (-2075 1725);
DISPLAY INVISIBLE (-2075 1725);
FORCEPROP 2 LAST ROOM PVCCIO_CPU1
J 0
(-2025 1875);
DISPLAY 1.361702 (-2025 1875);
PAINT ORANGE (-2025 1875);
DISPLAY INVISIBLE (-2025 1875);
FORCEPROP 1 LAST PATH I83
J 0
(-2025 1875);
DISPLAY 0.978723 (-2025 1875);
PAINT WHITE (-2025 1875);
DISPLAY INVISIBLE (-2025 1875);
FORCEPROP 2 LAST CDS_LOCATION C4D44
J 0
(-2025 1825);
DISPLAY 0.617021 (-2025 1825);
PAINT AQUA (-2025 1825);
DISPLAY INVISIBLE (-2025 1825);
FORCEPROP 2 LAST SEC 1
J 0
(-2025 1950);
DISPLAY 0.680851 (-2025 1950);
PAINT MONO (-2025 1950);
DISPLAY INVISIBLE (-2025 1950);
FORCEPROP 2 LAST SEC_TYPE 0402LF
J 0
(-2025 1950);
DISPLAY 1.021277 (-2025 1950);
PAINT ORANGE (-2025 1950);
DISPLAY INVISIBLE (-2025 1950);
FORCEADD RES..1
(-2325 1925);
FORCEPROP 1 LAST LOCATION R4E7
J 0
(-2375 1975);
DISPLAY 0.617021 (-2375 1975);
PAINT AQUA (-2375 1975);
FORCEPROP 1 LAST MATERIAL CHIP
J 0
(-2300 1775);
DISPLAY 0.617021 (-2300 1775);
PAINT SKYBLUE (-2300 1775);
FORCEPROP 1 LAST WATTAGE 1/16W
J 2
(-2325 1775);
DISPLAY 0.617021 (-2325 1775);
PAINT SKYBLUE (-2325 1775);
FORCEPROP 1 LAST TOLERANCE 1%
J 0
(-2400 1825);
DISPLAY 0.617021 (-2400 1825);
PAINT SKYBLUE (-2400 1825);
FORCEPROP 1 LAST PART_NUMBER G21796-066
J 0
(-2475 1875);
DISPLAY 0.617021 (-2475 1875);
PAINT BLUE (-2475 1875);
FORCEPROP 1 LASTPIN (-2225 1925) $PN 2
J 0
(-2263 1937);
DISPLAY 0.617021 (-2263 1937);
PAINT ORANGE (-2263 1937);
FORCEPROP 1 LASTPIN (-2425 1925) $PN 1
J 0
(-2413 1937);
DISPLAY 0.617021 (-2413 1937);
PAINT ORANGE (-2413 1937);
FORCEPROP 1 LAST VALUE 10.0
J 2
(-2425 1825);
DISPLAY 0.617021 (-2425 1825);
PAINT SKYBLUE (-2425 1825);
FORCEPROP 1 LAST PACK_TYPE 0402
J 0
(-2300 1825);
DISPLAY 0.617021 (-2300 1825);
PAINT SKYBLUE (-2300 1825);
FORCEPROP 2 LAST CDS_LOCATION R4E7
J 0
(-2375 1975);
DISPLAY 0.617021 (-2375 1975);
PAINT AQUA (-2375 1975);
DISPLAY INVISIBLE (-2375 1975);
FORCEPROP 2 LAST CDS_LIB mstr_discrete
J 0
(-2325 1925);
PAINT ORANGE (-2325 1925);
DISPLAY INVISIBLE (-2325 1925);
FORCEPROP 2 LAST ROOM PVCCIO_CPU1
J 0
(-2250 2025);
DISPLAY 1.361702 (-2250 2025);
PAINT ORANGE (-2250 2025);
DISPLAY INVISIBLE (-2250 2025);
FORCEPROP 1 LAST PATH I84
J 0
(-2375 2075);
DISPLAY 0.978723 (-2375 2075);
PAINT WHITE (-2375 2075);
DISPLAY INVISIBLE (-2375 2075);
FORCEPROP 2 LAST SEC 1
J 0
(-2375 2150);
DISPLAY 0.680851 (-2375 2150);
PAINT MONO (-2375 2150);
DISPLAY INVISIBLE (-2375 2150);
FORCEPROP 2 LAST SEC_TYPE 0402
J 0
(-2375 2150);
DISPLAY 1.021277 (-2375 2150);
PAINT ORANGE (-2375 2150);
DISPLAY INVISIBLE (-2375 2150);
FORCEADD OFFPAGE..1
(-3175 1925);
FORCEPROP 2 LAST $XR0 214 
J 0
(-3427 1925);
DISPLAY 0.638298 (-3427 1925);
PAINT MONO (-3427 1925);
FORCEPROP 2 LAST PATH I86
J 0
(-3450 1975);
DISPLAY 1.021277 (-3450 1975);
PAINT ORANGE (-3450 1975);
DISPLAY INVISIBLE (-3450 1975);
FORCEPROP 2 LAST CDS_LIB mstr_standard
J 0
(-3175 1925);
PAINT ORANGE (-3175 1925);
DISPLAY INVISIBLE (-3175 1925);
FORCEPROP 2 LAST ROOM PVCCIO_CPU1
J 0
(-3725 2000);
DISPLAY 1.361702 (-3725 2000);
PAINT ORANGE (-3725 2000);
DISPLAY INVISIBLE (-3725 2000);
FORCEPROP 1 LAST OFFPAGE TRUE
J 0
(-2850 1800);
DISPLAY 1.170213 (-2850 1800);
PAINT GREEN (-2850 1800);
DISPLAY INVISIBLE (-2850 1800);
FORCEPROP 1 LAST COMMENT_BODY TRUE
J 0
(-3050 1825);
DISPLAY 1.170213 (-3050 1825);
PAINT GREEN (-3050 1825);
DISPLAY INVISIBLE (-3050 1825);
FORCEADD OFFPAGE..1
(-3175 1525);
FORCEPROP 2 LAST $XR0 214 
J 0
(-3427 1525);
DISPLAY 0.638298 (-3427 1525);
PAINT MONO (-3427 1525);
FORCEPROP 2 LAST ROOM PVCCIO_CPU1
J 0
(-3725 1600);
DISPLAY 1.361702 (-3725 1600);
PAINT ORANGE (-3725 1600);
DISPLAY INVISIBLE (-3725 1600);
FORCEPROP 2 LAST CDS_LIB mstr_standard
J 0
(-3175 1525);
PAINT ORANGE (-3175 1525);
DISPLAY INVISIBLE (-3175 1525);
FORCEPROP 2 LAST PATH I87
J 0
(-3450 1575);
DISPLAY 1.021277 (-3450 1575);
PAINT ORANGE (-3450 1575);
DISPLAY INVISIBLE (-3450 1575);
FORCEPROP 1 LAST OFFPAGE TRUE
J 0
(-2850 1400);
DISPLAY 1.170213 (-2850 1400);
PAINT GREEN (-2850 1400);
DISPLAY INVISIBLE (-2850 1400);
FORCEPROP 1 LAST COMMENT_BODY TRUE
J 0
(-3050 1425);
DISPLAY 1.170213 (-3050 1425);
PAINT GREEN (-3050 1425);
DISPLAY INVISIBLE (-3050 1425);
FORCEADD CAP_A..1
(2425 1575);
FORCEPROP 1 LASTPIN (2425 1475) $PN 2
J 0
(2435 1455);
DISPLAY 0.617021 (2435 1455);
PAINT ORANGE (2435 1455);
FORCEPROP 1 LAST PART_NUMBER D97712-004
J 0
(2475 1425);
DISPLAY 0.617021 (2475 1425);
PAINT BLUE (2475 1425);
FORCEPROP 1 LAST VOLTAGE 6.3V
J 0
(2475 1575);
DISPLAY 0.617021 (2475 1575);
PAINT SKYBLUE (2475 1575);
FORCEPROP 1 LAST VALUE 1.0UF
J 0
(2475 1625);
DISPLAY 0.617021 (2475 1625);
PAINT SKYBLUE (2475 1625);
FORCEPROP 1 LASTPIN (2425 1675) $PN 1
J 0
(2435 1655);
DISPLAY 0.617021 (2435 1655);
PAINT ORANGE (2435 1655);
FORCEPROP 1 LAST TOLERANCE 10%
J 0
(2475 1525);
DISPLAY 0.617021 (2475 1525);
PAINT SKYBLUE (2475 1525);
FORCEPROP 1 LAST MATERIAL X6S
J 0
(2475 1475);
DISPLAY 0.617021 (2475 1475);
PAINT SKYBLUE (2475 1475);
FORCEPROP 1 LAST PACK_TYPE 0402V
J 0
(2475 1375);
DISPLAY 0.617021 (2475 1375);
PAINT SKYBLUE (2475 1375);
FORCEPROP 1 LAST LOCATION C4D31
J 0
(2475 1675);
DISPLAY 0.617021 (2475 1675);
PAINT AQUA (2475 1675);
FORCEPROP 2 LAST CDS_LIB dev_discrete
J 0
(2425 1575);
PAINT ORANGE (2425 1575);
DISPLAY INVISIBLE (2425 1575);
FORCEPROP 2 LAST CDS_LOCATION C4D31
J 0
(2475 1675);
DISPLAY 0.617021 (2475 1675);
PAINT AQUA (2475 1675);
DISPLAY INVISIBLE (2475 1675);
FORCEPROP 2 LAST CDS_SEC 1
J 0
(2475 1725);
PAINT ORANGE (2475 1725);
DISPLAY INVISIBLE (2475 1725);
FORCEPROP 1 LAST PATH I9
J 0
(2475 1725);
DISPLAY 0.978723 (2475 1725);
PAINT WHITE (2475 1725);
DISPLAY INVISIBLE (2475 1725);
FORCEPROP 2 LAST ROOM PVCCIO_CPU1
J 0
(2475 1725);
DISPLAY 1.361702 (2475 1725);
PAINT ORANGE (2475 1725);
DISPLAY INVISIBLE (2475 1725);
FORCEPROP 2 LAST SEC_TYPE 0402V
J 0
(2475 1775);
DISPLAY 1.021277 (2475 1775);
PAINT ORANGE (2475 1775);
DISPLAY INVISIBLE (2475 1775);
FORCEPROP 2 LAST SEC 1
J 0
(2475 1775);
DISPLAY 0.680851 (2475 1775);
PAINT MONO (2475 1775);
DISPLAY INVISIBLE (2475 1775);
FORCEADD RES..1
(-1925 3225);
FORCEPROP 1 LAST PART_NUMBER G21497-005
J 0
(-2075 3175);
DISPLAY 0.617021 (-2075 3175);
PAINT BLUE (-2075 3175);
FORCEPROP 1 LAST TOLERANCE 5%
J 0
(-1975 3125);
DISPLAY 0.617021 (-1975 3125);
PAINT SKYBLUE (-1975 3125);
FORCEPROP 1 LAST WATTAGE 1/16W
J 2
(-1950 3075);
DISPLAY 0.617021 (-1950 3075);
PAINT SKYBLUE (-1950 3075);
FORCEPROP 1 LAST PACK_TYPE 0402
J 0
(-1850 3125);
DISPLAY 0.617021 (-1850 3125);
PAINT SKYBLUE (-1850 3125);
FORCEPROP 1 LAST MATERIAL CHIP
J 0
(-1925 3075);
DISPLAY 0.617021 (-1925 3075);
PAINT SKYBLUE (-1925 3075);
FORCEPROP 1 LAST VALUE 0.0
J 2
(-2025 3125);
DISPLAY 0.617021 (-2025 3125);
PAINT SKYBLUE (-2025 3125);
FORCEPROP 1 LASTPIN (-1825 3225) $PN 2
J 0
(-1863 3237);
DISPLAY 0.787234 (-1863 3237);
PAINT ORANGE (-1863 3237);
FORCEPROP 1 LAST LOCATION R6P41
J 0
(-1975 3275);
DISPLAY 0.617021 (-1975 3275);
PAINT AQUA (-1975 3275);
FORCEPROP 1 LASTPIN (-2025 3225) $PN 1
J 0
(-2013 3237);
DISPLAY 0.787234 (-2013 3237);
PAINT ORANGE (-2013 3237);
FORCEPROP 2 LAST SEC_TYPE 0402
J 0
(-1975 3425);
DISPLAY 1.021277 (-1975 3425);
PAINT ORANGE (-1975 3425);
DISPLAY INVISIBLE (-1975 3425);
FORCEPROP 2 LAST SEC 1
J 0
(-1975 3425);
PAINT MONO (-1975 3425);
DISPLAY INVISIBLE (-1975 3425);
FORCEPROP 2 LAST CDS_LOCATION R6P41
J 0
(-1975 3275);
DISPLAY 0.617021 (-1975 3275);
PAINT AQUA (-1975 3275);
DISPLAY INVISIBLE (-1975 3275);
FORCEPROP 2 LAST CDS_LIB mstr_discrete
J 0
(-1925 3225);
PAINT ORANGE (-1925 3225);
DISPLAY INVISIBLE (-1925 3225);
FORCEPROP 2 LAST ROOM PVCCIN_CPU0_VR
J 0
(-1975 3325);
DISPLAY 1.361702 (-1975 3325);
PAINT ORANGE (-1975 3325);
DISPLAY INVISIBLE (-1975 3325);
FORCEPROP 1 LAST PATH I90
J 0
(-1975 3375);
DISPLAY 0.978723 (-1975 3375);
PAINT WHITE (-1975 3375);
DISPLAY INVISIBLE (-1975 3375);
FORCEADD RES..2
(-1025 4275);
FORCEPROP 1 LAST PACK_TYPE 0402
J 0
(-985 4100);
DISPLAY 0.617021 (-985 4100);
PAINT SKYBLUE (-985 4100);
FORCEPROP 1 LAST WATTAGE 1/16W
J 0
(-985 4250);
DISPLAY 0.617021 (-985 4250);
PAINT SKYBLUE (-985 4250);
FORCEPROP 1 LAST VALUE 100.0K
J 0
(-980 4350);
DISPLAY 0.617021 (-980 4350);
PAINT SKYBLUE (-980 4350);
FORCEPROP 1 LAST LOCATION R6P40
J 0
(-980 4400);
DISPLAY 0.617021 (-980 4400);
PAINT AQUA (-980 4400);
FORCEPROP 1 LASTPIN (-1025 4375) $PN 1
J 0
(-1020 4337);
DISPLAY 0.787234 (-1020 4337);
PAINT ORANGE (-1020 4337);
FORCEPROP 1 LAST TOLERANCE 1%
J 0
(-980 4300);
DISPLAY 0.617021 (-980 4300);
PAINT SKYBLUE (-980 4300);
FORCEPROP 1 LAST MATERIAL EMPTY
J 0
(-985 4200);
DISPLAY 0.617021 (-985 4200);
PAINT RED (-985 4200);
FORCEPROP 1 LASTPIN (-1025 4175) $PN 2
J 0
(-1020 4185);
DISPLAY 0.787234 (-1020 4185);
PAINT ORANGE (-1020 4185);
FORCEPROP 1 LAST PART_NUMBER G21796-010
J 0
(-985 4150);
DISPLAY 0.617021 (-985 4150);
PAINT BLUE (-985 4150);
FORCEPROP 2 LAST SEC_TYPE 0402
J 0
(-975 4500);
DISPLAY 1.021277 (-975 4500);
PAINT ORANGE (-975 4500);
DISPLAY INVISIBLE (-975 4500);
FORCEPROP 2 LAST SEC 1
J 0
(-975 4500);
PAINT MONO (-975 4500);
DISPLAY INVISIBLE (-975 4500);
FORCEPROP 2 LAST CDS_LIB mstr_discrete
J 0
(-1025 4275);
PAINT ORANGE (-1025 4275);
DISPLAY INVISIBLE (-1025 4275);
FORCEPROP 0 LAST ROOM BMC
J 0
(-975 4500);
DISPLAY 0.617021 (-975 4500);
PAINT ORANGE (-975 4500);
DISPLAY INVISIBLE (-975 4500);
FORCEPROP 1 LAST PATH I91
J 0
(-975 4450);
DISPLAY 0.978723 (-975 4450);
PAINT WHITE (-975 4450);
DISPLAY INVISIBLE (-975 4450);
FORCEPROP 2 LAST CDS_LOCATION R6P40
J 0
(-980 4400);
DISPLAY 0.617021 (-980 4400);
PAINT AQUA (-980 4400);
DISPLAY INVISIBLE (-980 4400);
FORCEPROP 0 LAST BOM_COST SM_CONTROLLER
J 0
(-975 4600);
DISPLAY 1.021277 (-975 4600);
PAINT ORANGE (-975 4600);
DISPLAY INVISIBLE (-975 4600);
FORCEADD UNIVERSAL_POWER..1
(-2425 4975);
FORCEPROP 3 LASTPIN (-2425 4925) SIG_NAME VR_FET_SW_P12V_STBY_PVCCIN_CPU0\g
J 0
(-2415 4935);
DISPLAY 0.659574 (-2415 4935);
PAINT MONO (-2415 4935);
DISPLAY INVISIBLE (-2415 4935);
FORCEPROP 1 LAST HDL_POWER VR_FET_SW_P12V_STBY_PVCCIN_CPU0
J 1
(-2325 5025);
DISPLAY 0.617021 (-2325 5025);
PAINT GREEN (-2325 5025);
FORCEPROP 1 LAST PATH I92
J 0
(-2375 5000);
DISPLAY 0.872340 (-2375 5000);
PAINT AQUA (-2375 5000);
DISPLAY INVISIBLE (-2375 5000);
FORCEPROP 2 LAST CDS_LIB mstr_symbols
J 0
(-2425 4975);
PAINT ORANGE (-2425 4975);
DISPLAY INVISIBLE (-2425 4975);
FORCEADD PXE1110B..1
(175 2825);
FORCEPROP 2 LASTPIN (-275 3575) $PN 39
J 2
(-285 3585);
DISPLAY 0.617021 (-285 3585);
PAINT ORANGE (-285 3585);
FORCEPROP 1 LAST MATERIAL IC
J 0
(-225 3700);
DISPLAY 0.617021 (-225 3700);
PAINT SKYBLUE (-225 3700);
FORCEPROP 1 LAST LOCATION EU4D5
J 0
(-225 3750);
DISPLAY 0.617021 (-225 3750);
PAINT AQUA (-225 3750);
FORCEPROP 2 LASTPIN (625 3425) $PN 12
J 0
(635 3435);
DISPLAY 0.617021 (635 3435);
PAINT ORANGE (635 3435);
FORCEPROP 2 LASTPIN (-275 3125) $PN 37
J 2
(-285 3135);
DISPLAY 0.617021 (-285 3135);
PAINT ORANGE (-285 3135);
FORCEPROP 1 LAST PART_NUMBER H89187-001
J 0
(-225 1925);
DISPLAY 0.617021 (-225 1925);
PAINT BLUE (-225 1925);
FORCEPROP 2 LASTPIN (625 2775) $PN 18
J 0
(635 2785);
DISPLAY 0.617021 (635 2785);
PAINT ORANGE (635 2785);
FORCEPROP 2 LASTPIN (625 2675) $PN 13
J 0
(635 2685);
DISPLAY 0.617021 (635 2685);
PAINT ORANGE (635 2685);
FORCEPROP 2 LASTPIN (625 2725) $PN 14
J 0
(635 2735);
DISPLAY 0.617021 (635 2735);
PAINT ORANGE (635 2735);
FORCEPROP 2 LASTPIN (625 2275) $PN 41
J 0
(635 2285);
DISPLAY 0.617021 (635 2285);
PAINT ORANGE (635 2285);
FORCEPROP 2 LASTPIN (-275 3275) $PN 35
J 2
(-285 3285);
DISPLAY 0.617021 (-285 3285);
PAINT ORANGE (-285 3285);
FORCEPROP 2 LASTPIN (625 2825) $PN 31
J 0
(635 2835);
DISPLAY 0.617021 (635 2835);
PAINT ORANGE (635 2835);
FORCEPROP 2 LASTPIN (625 2875) $PN 32
J 0
(635 2885);
DISPLAY 0.617021 (635 2885);
PAINT ORANGE (635 2885);
FORCEPROP 2 LASTPIN (625 2475) $PN 4
J 0
(635 2485);
DISPLAY 0.617021 (635 2485);
PAINT ORANGE (635 2485);
FORCEPROP 2 LASTPIN (625 2375) $PN 1
J 0
(635 2385);
DISPLAY 0.617021 (635 2385);
PAINT ORANGE (635 2385);
FORCEPROP 2 LASTPIN (-275 2775) $PN 8
J 2
(-285 2785);
DISPLAY 0.617021 (-285 2785);
PAINT ORANGE (-285 2785);
FORCEPROP 2 LASTPIN (-275 3525) $PN 15
J 2
(-285 3535);
DISPLAY 0.617021 (-285 3535);
PAINT ORANGE (-285 3535);
FORCEPROP 2 LASTPIN (-275 3375) $PN 22
J 2
(-285 3385);
DISPLAY 0.617021 (-285 3385);
PAINT ORANGE (-285 3385);
FORCEPROP 2 LASTPIN (625 2075) $PN 27
J 0
(635 2085);
DISPLAY 0.617021 (635 2085);
PAINT ORANGE (635 2085);
FORCEPROP 2 LASTPIN (625 2125) $PN 23
J 0
(635 2135);
DISPLAY 0.617021 (635 2135);
PAINT ORANGE (635 2135);
FORCEPROP 2 LASTPIN (625 2425) $PN 2
J 0
(635 2435);
DISPLAY 0.617021 (635 2435);
PAINT ORANGE (635 2435);
FORCEPROP 2 LASTPIN (625 2975) $PN 5
J 0
(635 2985);
DISPLAY 0.617021 (635 2985);
PAINT ORANGE (635 2985);
FORCEPROP 2 LASTPIN (625 3025) $PN 3
J 0
(635 3035);
DISPLAY 0.617021 (635 3035);
PAINT ORANGE (635 3035);
FORCEPROP 2 LASTPIN (625 3125) $PN 17
J 0
(635 3135);
DISPLAY 0.617021 (635 3135);
PAINT ORANGE (635 3135);
FORCEPROP 2 LASTPIN (625 3225) $PN 11
J 0
(635 3235);
DISPLAY 0.617021 (635 3235);
PAINT ORANGE (635 3235);
FORCEPROP 2 LASTPIN (625 3575) $PN 9
J 0
(635 3585);
DISPLAY 0.617021 (635 3585);
PAINT ORANGE (635 3585);
FORCEPROP 2 LASTPIN (-275 3225) $PN 10
J 2
(-285 3235);
DISPLAY 0.617021 (-285 3235);
PAINT ORANGE (-285 3235);
FORCEPROP 2 LASTPIN (-275 3425) $PN 21
J 2
(-285 3435);
DISPLAY 0.617021 (-285 3435);
PAINT ORANGE (-285 3435);
FORCEPROP 2 LASTPIN (-275 3075) $PN 38
J 2
(-285 3085);
DISPLAY 0.617021 (-285 3085);
PAINT ORANGE (-285 3085);
FORCEPROP 2 LASTPIN (-275 2625) $PN 20
J 2
(-285 2635);
DISPLAY 0.617021 (-285 2635);
PAINT ORANGE (-285 2635);
FORCEPROP 2 LASTPIN (-275 2575) $PN 29
J 2
(-285 2585);
DISPLAY 0.617021 (-285 2585);
PAINT ORANGE (-285 2585);
FORCEPROP 2 LASTPIN (-275 2925) $PN 16
J 2
(-285 2935);
DISPLAY 0.617021 (-285 2935);
PAINT ORANGE (-285 2935);
FORCEPROP 2 LASTPIN (-275 2975) $PN 40
J 2
(-285 2985);
DISPLAY 0.617021 (-285 2985);
PAINT ORANGE (-285 2985);
FORCEPROP 2 LASTPIN (-275 2525) $PN 30
J 2
(-285 2535);
DISPLAY 0.617021 (-285 2535);
PAINT ORANGE (-285 2535);
FORCEPROP 2 LASTPIN (-275 2425) $PN 6
J 2
(-285 2435);
DISPLAY 0.617021 (-285 2435);
PAINT ORANGE (-285 2435);
FORCEPROP 2 LASTPIN (-275 2375) $PN 7
J 2
(-285 2385);
DISPLAY 0.617021 (-285 2385);
PAINT ORANGE (-285 2385);
FORCEPROP 2 LASTPIN (-275 2275) $PN 34
J 2
(-285 2285);
DISPLAY 0.617021 (-285 2285);
PAINT ORANGE (-285 2285);
FORCEPROP 2 LASTPIN (-275 2025) $PN 33
J 2
(-285 2035);
DISPLAY 0.617021 (-285 2035);
PAINT ORANGE (-285 2035);
FORCEPROP 2 LASTPIN (-275 2075) $PN 36
J 2
(-285 2085);
DISPLAY 0.617021 (-285 2085);
PAINT ORANGE (-285 2085);
FORCEPROP 2 LASTPIN (-275 2125) $PN 26
J 2
(-285 2135);
DISPLAY 0.617021 (-285 2135);
PAINT ORANGE (-285 2135);
FORCEPROP 2 LASTPIN (-275 2175) $PN 25
J 2
(-285 2185);
DISPLAY 0.617021 (-285 2185);
PAINT ORANGE (-285 2185);
FORCEPROP 2 LASTPIN (625 2525) $PN 24
J 0
(635 2535);
DISPLAY 0.617021 (635 2535);
PAINT ORANGE (635 2535);
FORCEPROP 2 LASTPIN (-275 2675) $PN 19
J 2
(-285 2685);
DISPLAY 0.617021 (-285 2685);
PAINT ORANGE (-285 2685);
FORCEPROP 2 LASTPIN (625 2575) $PN 28
J 0
(635 2585);
DISPLAY 0.617021 (635 2585);
PAINT ORANGE (635 2585);
FORCEPROP 2 LAST CDS_LOCATION EU4D5
J 0
(-225 3750);
PAINT WHITE (-225 3750);
DISPLAY INVISIBLE (-225 3750);
FORCEPROP 2 LAST SEC 1
J 0
(-225 3800);
DISPLAY 0.680851 (-225 3800);
PAINT MONO (-225 3800);
DISPLAY INVISIBLE (-225 3800);
FORCEPROP 2 LAST SEC_TYPE QFN
J 0
(-225 3800);
DISPLAY 1.021277 (-225 3800);
PAINT ORANGE (-225 3800);
DISPLAY INVISIBLE (-225 3800);
FORCEPROP 1 LAST PACK_TYPE QFN
J 0
(-225 3800);
PAINT SKYBLUE (-225 3800);
DISPLAY INVISIBLE (-225 3800);
FORCEPROP 1 LAST CDS_LMAN_SYM_OUTLINE -400,850,400,-850
J 0
(175 2825);
DISPLAY 0.468085 (175 2825);
PAINT GREEN (175 2825);
DISPLAY INVISIBLE (175 2825);
FORCEPROP 2 LAST CDS_LIB mstr_controller
J 0
(175 2825);
PAINT ORANGE (175 2825);
DISPLAY INVISIBLE (175 2825);
FORCEPROP 1 LAST PATH I96
J 0
(275 3701);
PAINT WHITE (275 3701);
DISPLAY INVISIBLE (275 3701);
FORCEADD SC22P50V2JN-4GP..1
R 1
(-1900 3500);
FORCEPROP 2 LAST ATTRIBUTE 22PF
J 0
(-1500 3550);
DISPLAY 0.638298 (-1500 3550);
PAINT GREEN (-1500 3550);
FORCEPROP 2 LAST TYPE NPO
J 0
(-1500 3500);
DISPLAY 0.638298 (-1500 3500);
PAINT GREEN (-1500 3500);
FORCEPROP 2 LAST RATED 50V
J 0
(-1250 3550);
DISPLAY 0.638298 (-1250 3550);
PAINT GREEN (-1250 3550);
FORCEPROP 1 LAST LOCATION CF14
J 0
(-2030 3550);
DISPLAY 0.617021 (-2030 3550);
PAINT GREEN (-2030 3550);
FORCEPROP 2 LAST PACK_SIZE 0402
J 0
(-1350 3500);
DISPLAY 0.638298 (-1350 3500);
PAINT GREEN (-1350 3500);
FORCEPROP 2 LAST TOLERANCE 5%
J 0
(-1350 3550);
DISPLAY 0.638298 (-1350 3550);
PAINT GREEN (-1350 3550);
FORCEPROP 0 LAST GROUP POWER_FAIR
J 0
(-2012 3428);
DISPLAY 0.638298 (-2012 3428);
PAINT BROWN (-2012 3428);
DISPLAY BOTH (-2012 3428);
FORCEPROP 1 LAST VALUE SC22P50V2JN-4GP
J 0
(-1925 3550);
DISPLAY 0.617021 (-1925 3550);
PAINT GREEN (-1925 3550);
FORCEPROP 1 LAST PART_NUMBER 78.22034.1FL
R 1
J 0
(-1900 3500);
DISPLAY 0.617021 (-1900 3500);
PAINT GREEN (-1900 3500);
DISPLAY INVISIBLE (-1900 3500);
FORCEPROP 1 LAST PACK_TYPE SMD-BCG
R 1
J 0
(-1900 3500);
DISPLAY 0.617021 (-1900 3500);
PAINT GREEN (-1900 3500);
DISPLAY INVISIBLE (-1900 3500);
FORCEPROP 1 LAST CDS_LMAN_SYM_OUTLINE -50,25,50,-25
R 1
J 0
(-1900 3500);
DISPLAY 0.468085 (-1900 3500);
PAINT GREEN (-1900 3500);
DISPLAY INVISIBLE (-1900 3500);
FORCEPROP 1 LAST PATH I98
R 1
J 0
(-1900 3500);
DISPLAY 0.617021 (-1900 3500);
PAINT GREEN (-1900 3500);
DISPLAY INVISIBLE (-1900 3500);
FORCEPROP 2 LAST CDS_LIB w_hdl
J 0
(-1900 3500);
PAINT MONO (-1900 3500);
DISPLAY INVISIBLE (-1900 3500);
FORCEADD RES..1
(-1900 3725);
FORCEPROP 1 LAST PACK_TYPE 0402
J 0
(-1825 3825);
DISPLAY 0.617021 (-1825 3825);
PAINT SKYBLUE (-1825 3825);
FORCEPROP 1 LAST VALUE 1.0K
J 2
(-1875 3775);
DISPLAY 0.617021 (-1875 3775);
PAINT SKYBLUE (-1875 3775);
FORCEPROP 1 LASTPIN (-2000 3725) $PN 1
J 0
(-1988 3737);
DISPLAY 0.787234 (-1988 3737);
PAINT ORANGE (-1988 3737);
FORCEPROP 1 LAST LOCATION RF14
J 0
(-2075 3775);
DISPLAY 0.617021 (-2075 3775);
PAINT AQUA (-2075 3775);
FORCEPROP 1 LAST PART_NUMBER G85996-004
J 0
(-2050 3825);
DISPLAY 0.617021 (-2050 3825);
PAINT BLUE (-2050 3825);
FORCEPROP 1 LASTPIN (-1800 3725) $PN 2
J 0
(-1838 3737);
DISPLAY 0.787234 (-1838 3737);
PAINT ORANGE (-1838 3737);
FORCEPROP 1 LAST TOLERANCE 0.1%
J 0
(-1850 3775);
DISPLAY 0.617021 (-1850 3775);
PAINT SKYBLUE (-1850 3775);
FORCEPROP 0 LAST FAIR_SS 064.9090D.M001
J 0
(-2000 3625);
DISPLAY 0.638298 (-2000 3625);
PAINT BROWN (-2000 3625);
DISPLAY BOTH (-2000 3625);
FORCEPROP 0 LAST GROUP POWER_FAIR
J 0
(-2000 3675);
DISPLAY 0.638298 (-2000 3675);
PAINT BROWN (-2000 3675);
DISPLAY BOTH (-2000 3675);
FORCEPROP 1 LAST WATTAGE 1/16W
J 2
(-1600 3775);
DISPLAY 0.617021 (-1600 3775);
PAINT SKYBLUE (-1600 3775);
FORCEPROP 1 LAST MATERIAL CHIP
J 0
(-1725 3825);
DISPLAY 0.617021 (-1725 3825);
PAINT SKYBLUE (-1725 3825);
FORCEPROP 1 LAST PATH I99
J 0
(-1950 3875);
DISPLAY 0.978723 (-1950 3875);
PAINT WHITE (-1950 3875);
DISPLAY INVISIBLE (-1950 3875);
FORCEPROP 0 LAST ROOM SB
J 0
(-1850 3950);
DISPLAY 1.021277 (-1850 3950);
PAINT ORANGE (-1850 3950);
DISPLAY INVISIBLE (-1850 3950);
FORCEPROP 2 LAST CDS_LIB mstr_discrete
J 0
(-1900 3725);
PAINT MONO (-1900 3725);
DISPLAY INVISIBLE (-1900 3725);
FORCEPROP 0 LAST SEC 1
J 0
(-1825 3875);
DISPLAY 0.680851 (-1825 3875);
PAINT MONO (-1825 3875);
DISPLAY INVISIBLE (-1825 3875);
FORCEPROP 2 LAST SEC_TYPE 0402
J 0
(-1950 3925);
DISPLAY 1.021277 (-1950 3925);
PAINT ORANGE (-1950 3925);
DISPLAY INVISIBLE (-1950 3925);
FORCEADD DNS..2
(1605 4070);
PAINT RED (1605 4070);
FORCEPROP 2 LAST CDS_LIB mstr_misc
J 0
(1605 4070);
PAINT ORANGE (1605 4070);
DISPLAY INVISIBLE (1605 4070);
FORCEPROP 1 LAST COMMENT_BODY TRUE
R 1
J 0
(1680 3845);
DISPLAY 0.872340 (1680 3845);
PAINT GREEN (1680 3845);
DISPLAY INVISIBLE (1680 3845);
FORCEADD DNS..2
(-1020 4270);
PAINT RED (-1020 4270);
FORCEPROP 1 LAST COMMENT_BODY TRUE
R 1
J 0
(-945 4045);
DISPLAY 0.872340 (-945 4045);
PAINT GREEN (-945 4045);
DISPLAY INVISIBLE (-945 4045);
FORCEPROP 2 LAST CDS_LIB mstr_misc
J 0
(-1020 4270);
PAINT ORANGE (-1020 4270);
DISPLAY INVISIBLE (-1020 4270);
FORCEADD INTEL_CORP_BPAGE..1
(4250 200);
FORCEPROP 1 LAST CDS_CON_LAST_MODIFIED Fri Jun 16 17:49:17 2017
J 0
(2825 525);
PAINT ORANGE (2825 525);
DISPLAY INVISIBLE (2825 525);
FORCEPROP 1 LAST CUSTOM_TXT_CDS <CURRENT_DESIGN_SHEET> OF <TOTAL_DESIGN_SHEETS>
J 0
(3750 225);
PAINT ORANGE (3750 225);
FORCEPROP 1 LAST CUSTOM_TXT_CDS <CON_LAST_MODIFIED>
J 0
(250 300);
PAINT ORANGE (250 300);
FORCEPROP 2 LAST CUSTOM_TXT_CDS <XR_PAGE_TITLE>
J 0
(-3640 5450);
DISPLAY 0.638298 (-3640 5450);
PAINT PINK (-3640 5450);
DISPLAY INVISIBLE (-3640 5450);
FORCEPROP 1 LAST SCH_TITLE PVCCIO CPU1 (1 OF 2)
J 0
(-3700 250);
DISPLAY 1.212766 (-3700 250);
PAINT ORANGE (-3700 250);
FORCEPROP 2 LAST PAGE_BORDER TRUE
J 0
(-3640 5450);
DISPLAY 0.638298 (-3640 5450);
PAINT PINK (-3640 5450);
DISPLAY INVISIBLE (-3640 5450);
FORCEPROP 2 LAST CDS_LIB mstr_symbols
J 0
(4250 200);
PAINT MONO (4250 200);
DISPLAY INVISIBLE (4250 200);
FORCEPROP 1 LAST COMMENT_BODY TRUE
J 0
(4262 212);
DISPLAY 0.468085 (4262 212);
PAINT GREEN (4262 212);
DISPLAY INVISIBLE (4262 212);
FORCEPROP 2 LAST CDS_XR_PAGE_TITLE CR-213 : @BASEBOARD_FAB2_LIB.BASEBOARD_FAB2(SCH_1):PAGE213
J 0
(-3640 5450);
DISPLAY 0.638298 (-3640 5450);
PAINT PINK (-3640 5450);
DISPLAY INVISIBLE (-3640 5450);
FORCEADD DNS..2
(-1445 4470);
PAINT RED (-1445 4470);
FORCEPROP 2 LAST CDS_LIB mstr_misc
J 0
(-1445 4470);
PAINT ORANGE (-1445 4470);
DISPLAY INVISIBLE (-1445 4470);
FORCEPROP 1 LAST COMMENT_BODY TRUE
R 1
J 0
(-1370 4245);
DISPLAY 0.872340 (-1370 4245);
PAINT GREEN (-1370 4245);
DISPLAY INVISIBLE (-1370 4245);
FORCEADD DESIGN_NOTE..1
(-225 1675);
FORCEPROP 0 LAST L1 SMBUS ADDRESS: 0XB4
J 0
(-425 1550);
DISPLAY 1.021277 (-425 1550);
PAINT VIOLET (-425 1550);
FORCEPROP 2 LAST CDS_LIB mstr_symbols
J 0
(-225 1675);
PAINT ORANGE (-225 1675);
DISPLAY INVISIBLE (-225 1675);
FORCEPROP 1 LAST COMMENT_BODY TRUE
J 0
(-200 1775);
DISPLAY 0.978723 (-200 1775);
PAINT ORANGE (-200 1775);
DISPLAY INVISIBLE (-200 1775);
FORCEADD DNS..2
(-2045 4420);
PAINT RED (-2045 4420);
FORCEPROP 2 LAST CDS_LIB mstr_misc
J 0
(-2045 4420);
PAINT ORANGE (-2045 4420);
DISPLAY INVISIBLE (-2045 4420);
FORCEPROP 1 LAST COMMENT_BODY TRUE
R 1
J 0
(-1970 4195);
DISPLAY 0.872340 (-1970 4195);
PAINT GREEN (-1970 4195);
DISPLAY INVISIBLE (-1970 4195);
FORCEADD DESIGN_NOTE..1
(2900 4975);
FORCEPROP 0 LAST L2 PVCCIO_CPU1: 0X02(BUS #1)
J 0
(2700 4775);
DISPLAY 1.021277 (2700 4775);
PAINT VIOLET (2700 4775);
FORCEPROP 0 LAST L1 SVID ADDRESS
J 0
(2700 4850);
DISPLAY 1.021277 (2700 4850);
PAINT VIOLET (2700 4850);
FORCEPROP 2 LAST CDS_LIB mstr_symbols
J 0
(2900 4975);
PAINT ORANGE (2900 4975);
DISPLAY INVISIBLE (2900 4975);
FORCEPROP 1 LAST COMMENT_BODY TRUE
J 0
(2925 5075);
DISPLAY 0.978723 (2925 5075);
PAINT ORANGE (2925 5075);
DISPLAY INVISIBLE (2925 5075);
WIRE 16 -1 (1875 4500)(1875 4675);
WIRE 16 -1 (1875 4500)(1600 4500);
WIRE 16 -1 (2175 4500)(1875 4500);
WIRE 16 -1 (2175 4150)(2175 4500);
WIRE 16 -1 (950 4500)(1600 4500);
WIRE 16 -1 (1600 4175)(1600 4500);
WIRE 16 -1 (950 4150)(950 4500);
WIRE 16 -1 (2425 1325)(2425 1475);
WIRE 16 -1 (-2100 2600)(-2100 2650);
WIRE 16 -1 (2025 1425)(2025 1475);
WIRE 16 -1 (150 4000)(150 4050);
WIRE 16 -1 (1000 1925)(1000 2075);
WIRE 16 -1 (1000 2075)(1000 2125);
WIRE 16 -1 (625 2075)(1000 2075);
WIRE 16 -1 (1000 2275)(1000 2125);
WIRE 16 -1 (1000 2125)(625 2125);
WIRE 16 -1 (625 2275)(1000 2275);
WIRE 16 -1 (-550 4675)(-550 4775);
WIRE 16 -1 (-1025 4675)(-550 4675);
WIRE 16 -1 (-550 4600)(-550 4675);
WIRE 16 -1 (-1025 4375)(-1025 4675);
WIRE 16 -1 (-1450 4575)(-1450 4850);
WIRE 16 -1 (-2050 4525)(-2050 4825);
WIRE 16 -1 (-250 4000)(-250 4050);
WIRE 16 -1 (-850 900)(-850 800);
WIRE 16 -1 (-525 900)(-850 900);
WIRE 16 -1 (-850 1075)(-850 900);
WIRE 16 -1 (-525 1075)(-525 900);
WIRE 16 -1 (-950 2075)(-950 2125);
WIRE 16 -1 (-275 2125)(-950 2125);
WIRE 16 -1 (-2425 4050)(-2425 4150);
WIRE 16 -1 (-2850 4075)(-2850 4150);
WIRE 16 -1 (1750 2600)(1750 2550);
WIRE 16 -1 (-2425 4800)(-2425 4925);
WIRE 16 -1 (-2225 1925)(-2075 1925);
FORCEPROP 0 LAST VOLTAGE 1.05
J 0
(-2075 2000);
DISPLAY 1.021277 (-2075 2000);
PAINT SKYBLUE (-2075 2000);
DISPLAY INVISIBLE (-2075 2000);
FORCEPROP 2 LAST SIG_NAME VR_PVCCIO_CPU1_AVSP
J 0
(-1865 2690);
DISPLAY 0.617021 (-1865 2690);
PAINT ORANGE (-1865 2690);
FORCEPROP 2 LASTPROP $XRERR UNIQUE?
J 0
(-2105 2690);
DISPLAY 0.638298 (-2105 2690);
PAINT MONO (-2105 2690);
DISPLAY INVISIBLE (-2105 2690);
WIRE 16 -1 (-2075 1825)(-2075 1925);
WIRE 16 -1 (-2075 1925)(-1900 1925);
WIRE 16 -1 (-1900 2675)(-1900 1925);
WIRE 16 -1 (-275 2675)(-1900 2675);
WIRE 16 -1 (-3125 1525)(-2075 1525);
FORCEPROP 2 LAST SIG_NAME VSENSE_PVCCIO_CPU1_AVSN
J 0
(-3140 1540);
DISPLAY 0.617021 (-3140 1540);
PAINT ORANGE (-3140 1540);
WIRE 16 -1 (-2075 1625)(-2075 1525);
WIRE 16 -1 (-1725 1525)(-2075 1525);
WIRE 16 -1 (-1725 1525)(-1725 2625);
WIRE 16 -1 (-275 2625)(-1725 2625);
WIRE 16 -1 (-2625 3225)(-2025 3225);
FORCEPROP 2 LAST SIG_NAME FM_PVCCIO_CPU1_EN
J 0
(-2625 3240);
DISPLAY 0.617021 (-2625 3240);
PAINT ORANGE (-2625 3240);
WIRE 16 -1 (-2100 3275)(-2100 2850);
WIRE 16 -1 (-2100 3275)(-275 3275);
WIRE 16 -1 (-2625 3275)(-2100 3275);
FORCEPROP 2 LAST SIG_NAME A_TSENSE_PVCCIO_CPU1
J 2
(-2127 3294);
DISPLAY 0.617021 (-2127 3294);
PAINT ORANGE (-2127 3294);
WIRE 16 -1 (-1800 3725)(-1550 3725);
WIRE 16 -1 (-1825 3500)(-1550 3500);
WIRE 16 -1 (-1550 3725)(-1550 3500);
WIRE 16 -1 (-1550 3500)(-1550 3375);
WIRE 16 -1 (-275 3375)(-1550 3375);
WIRE 16 -1 (-2625 3375)(-1550 3375);
FORCEPROP 2 LAST SIG_NAME ISENSE_PVCCIO_CPU1_PH1_IMON
J 2
(-2017 3395);
DISPLAY 0.617021 (-2017 3395);
PAINT ORANGE (-2017 3395);
WIRE 16 -1 (-2075 3725)(-2000 3725);
WIRE 16 -1 (-2075 3425)(-2625 3425);
FORCEPROP 2 LAST SIG_NAME VR_PVCCIO_CPU1_AIREF1
J 0
(-2650 3440);
DISPLAY 0.617021 (-2650 3440);
PAINT ORANGE (-2650 3440);
WIRE 16 -1 (-275 3425)(-2075 3425);
WIRE 16 -1 (-2075 3500)(-2075 3425);
WIRE 16 -1 (-2075 3725)(-2075 3500);
WIRE 16 -1 (-1975 3500)(-2075 3500);
WIRE 3 2175 (-3700 3575)(-3150 3575);
WIRE 3 2175 (-3150 3575)(-3150 3900);
WIRE 3 2175 (-3700 3575)(-3700 3900);
WIRE 3 2175 (-3700 3900)(-3150 3900);
WIRE 3 682 (-2800 3850)(-2800 3650);
WIRE 3 682 (-2200 3850)(-2800 3850);
WIRE 3 682 (-2800 3650)(-2200 3650);
WIRE 3 682 (-2200 3650)(-2200 3850);
WIRE 16 -1 (-1925 3925)(-2050 3925);
WIRE 16 -1 (-2050 4325)(-2050 3925);
WIRE 16 -1 (-2825 3925)(-2050 3925);
FORCEPROP 0 LAST SIG_NAME SVID_CLK0_CPU1_R
J 0
(-2875 3935);
DISPLAY 0.617021 (-2875 3935);
PAINT ORANGE (-2875 3935);
WIRE 3 682 (-2500 4000)(-2950 4000);
WIRE 3 682 (-2950 4475)(-2950 4000);
WIRE 3 682 (-2500 4000)(-2500 4475);
WIRE 3 682 (-2500 4475)(-2950 4475);
WIRE 16 -1 (-275 2075)(-850 2075);
FORCEPROP 0 LAST VOLTAGE 3.3
J 0
(-550 2125);
DISPLAY 1.021277 (-550 2125);
PAINT SKYBLUE (-550 2125);
DISPLAY INVISIBLE (-550 2125);
WIRE 16 -1 (-850 1275)(-850 2075);
FORCEPROP 0 LAST SIG_NAME VR_PVCCIO_CPU1_XADDR1
R 1
J 0
(-860 1435);
DISPLAY 0.617021 (-860 1435);
PAINT ORANGE (-860 1435);
FORCEPROP 2 LASTPROP $XRERR UNIQUE?
J 0
(-1100 1435);
DISPLAY 0.638298 (-1100 1435);
PAINT MONO (-1100 1435);
DISPLAY INVISIBLE (-1100 1435);
WIRE 16 -1 (-525 2025)(-275 2025);
FORCEPROP 0 LAST VOLTAGE 3.3
J 0
(-400 2075);
DISPLAY 1.021277 (-400 2075);
PAINT SKYBLUE (-400 2075);
DISPLAY INVISIBLE (-400 2075);
WIRE 16 -1 (-525 1275)(-525 2025);
FORCEPROP 0 LAST SIG_NAME VR_PVCCIO_CPU1_XADDR2
R 1
J 0
(-535 1410);
DISPLAY 0.617021 (-535 1410);
PAINT ORANGE (-535 1410);
FORCEPROP 2 LASTPROP $XRERR UNIQUE?
J 0
(-775 1410);
DISPLAY 0.638298 (-775 1410);
PAINT MONO (-775 1410);
DISPLAY INVISIBLE (-775 1410);
WIRE 16 -1 (-550 3575)(-275 3575);
FORCEPROP 0 LAST VOLTAGE 3.3
J 0
(-400 3625);
DISPLAY 1.021277 (-400 3625);
PAINT SKYBLUE (-400 3625);
DISPLAY INVISIBLE (-400 3625);
WIRE 16 -1 (-550 4300)(-550 3575);
FORCEPROP 2 LAST SIG_NAME VR_PVCCIO_CPU1_VDD
R 1
J 0
(-550 3715);
DISPLAY 0.617021 (-550 3715);
PAINT ORANGE (-550 3715);
FORCEPROP 2 LASTPROP $XRERR UNIQUE?
J 0
(-790 3715);
DISPLAY 0.638298 (-790 3715);
PAINT MONO (-790 3715);
DISPLAY INVISIBLE (-790 3715);
WIRE 16 -1 (-550 4400)(-550 4300);
WIRE 16 -1 (-250 4300)(-550 4300);
WIRE 16 -1 (-250 4250)(-250 4300);
WIRE 16 -1 (150 4300)(-250 4300);
WIRE 16 -1 (150 4250)(150 4300);
WIRE 16 -1 (-275 3525)(-850 3525);
WIRE 16 -1 (-850 3525)(-850 3925);
WIRE 16 -1 (-1725 3925)(-850 3925);
FORCEPROP 2 LAST SIG_NAME SVID_CLK_PVCCIO_CPU1
J 0
(-1590 3940);
DISPLAY 0.617021 (-1590 3940);
PAINT ORANGE (-1590 3940);
FORCEPROP 2 LASTPROP $XRERR UNIQUE?
J 0
(-1830 3940);
DISPLAY 0.638298 (-1830 3940);
PAINT MONO (-1830 3940);
DISPLAY INVISIBLE (-1830 3940);
WIRE 16 -1 (-1825 3225)(-1025 3225);
FORCEPROP 2 LAST SIG_NAME VR_PVCCIO_CPU1_EN
J 0
(-1650 3240);
DISPLAY 0.617021 (-1650 3240);
PAINT ORANGE (-1650 3240);
FORCEPROP 2 LASTPROP $XRERR UNIQUE?
J 0
(-1890 3240);
DISPLAY 0.638298 (-1890 3240);
PAINT MONO (-1890 3240);
DISPLAY INVISIBLE (-1890 3240);
WIRE 16 -1 (-1025 4175)(-1025 3225);
WIRE 16 -1 (-275 3225)(-1025 3225);
FORCEPROP 0 LAST VOLTAGE 3.3
J 0
(-650 3275);
DISPLAY 1.021277 (-650 3275);
PAINT SKYBLUE (-650 3275);
DISPLAY INVISIBLE (-650 3275);
WIRE 3 2175 (-2125 3850)(-1100 3850);
WIRE 3 2175 (-1100 3350)(-1100 3850);
WIRE 3 2175 (-2125 3350)(-2125 3850);
WIRE 3 2175 (-2125 3350)(-1100 3350);
WIRE 16 -1 (-1275 2925)(-1450 2925);
WIRE 16 -1 (-1450 4375)(-1450 2925);
WIRE 16 -1 (-2625 2925)(-1450 2925);
FORCEPROP 2 LAST SIG_NAME SVID_DIO0_CPU1_R
J 0
(-2575 2935);
DISPLAY 0.617021 (-2575 2935);
PAINT ORANGE (-2575 2935);
WIRE 16 -1 (-275 2425)(-2625 2425);
FORCEPROP 2 LAST SIG_NAME SMB_VR_STBY_LVC3_SDA
J 0
(-2650 2440);
DISPLAY 0.617021 (-2650 2440);
PAINT ORANGE (-2650 2440);
WIRE 3 682 (-400 2525)(-350 2525);
WIRE 3 682 (-400 2575)(-400 2525);
WIRE 3 682 (-350 2575)(-400 2575);
WIRE 16 -1 (-1075 2925)(-275 2925);
FORCEPROP 2 LAST SIG_NAME SVID_VDIO_PVCCIO_CPU1
J 0
(-975 2940);
DISPLAY 0.617021 (-975 2940);
PAINT ORANGE (-975 2940);
FORCEPROP 2 LASTPROP $XRERR UNIQUE?
J 0
(-1215 2940);
DISPLAY 0.638298 (-1215 2940);
PAINT MONO (-1215 2940);
DISPLAY INVISIBLE (-1215 2940);
WIRE 16 -1 (2175 3950)(2175 3225);
WIRE 16 -1 (625 3225)(2175 3225);
FORCEPROP 2 LAST SIG_NAME IRQ_PVCCIO_CPU1_VRHOT_N
J 0
(750 3240);
DISPLAY 0.617021 (750 3240);
PAINT ORANGE (750 3240);
FORCEPROP 2 LASTPROP $XRERR UNIQUE?
J 0
(510 3240);
DISPLAY 0.638298 (510 3240);
PAINT MONO (510 3240);
DISPLAY INVISIBLE (510 3240);
WIRE 16 -1 (1350 3125)(625 3125);
FORCEPROP 2 LAST SIG_NAME SVID_ALERT_PVCCIO_CPU1
J 0
(725 3140);
DISPLAY 0.617021 (725 3140);
PAINT ORANGE (725 3140);
FORCEPROP 2 LASTPROP $XRERR UNIQUE?
J 0
(485 3140);
DISPLAY 0.638298 (485 3140);
PAINT MONO (485 3140);
DISPLAY INVISIBLE (485 3140);
WIRE 16 -1 (2725 2975)(625 2975);
FORCEPROP 0 LAST VOLTAGE 3.6
J 0
(2150 3050);
DISPLAY 1.021277 (2150 3050);
PAINT SKYBLUE (2150 3050);
DISPLAY INVISIBLE (2150 3050);
FORCEPROP 2 LAST SIG_NAME VR_PVCCIO_CPU1_PWM1
J 0
(2150 2990);
DISPLAY 0.617021 (2150 2990);
PAINT ORANGE (2150 2990);
WIRE 16 -1 (1600 3975)(1600 2875);
WIRE 16 -1 (625 2875)(1600 2875);
FORCEPROP 2 LAST SIG_NAME PU_VR_PVCCIO_CPU1_FAULT1
J 0
(725 2890);
DISPLAY 0.617021 (725 2890);
PAINT ORANGE (725 2890);
FORCEPROP 2 LASTPROP $XRERR UNIQUE?
J 0
(485 2890);
DISPLAY 0.638298 (485 2890);
PAINT MONO (485 2890);
DISPLAY INVISIBLE (485 2890);
WIRE 3 682 (700 2825)(750 2825);
WIRE 3 682 (750 2825)(750 2775);
WIRE 3 682 (750 2775)(800 2775);
WIRE 3 682 (750 2775)(750 2675);
WIRE 3 682 (750 2675)(700 2675);
WIRE 3 682 (750 2375)(700 2375);
WIRE 3 682 (750 2525)(750 2375);
WIRE 3 682 (750 2525)(800 2525);
WIRE 3 682 (750 2575)(750 2525);
WIRE 3 682 (700 2575)(750 2575);
WIRE 16 -1 (625 3575)(950 3575);
WIRE 16 -1 (950 3950)(950 3575);
WIRE 16 -1 (1750 3575)(950 3575);
FORCEPROP 2 LAST SIG_NAME PWRGD_PVCCIO_CPU1_R
J 0
(1035 3590);
DISPLAY 0.617021 (1035 3590);
PAINT ORANGE (1035 3590);
FORCEPROP 2 LASTPROP $XRERR UNIQUE?
J 0
(795 3590);
DISPLAY 0.638298 (795 3590);
PAINT MONO (795 3590);
DISPLAY INVISIBLE (795 3590);
WIRE 16 -1 (1750 2800)(1750 3575);
WIRE 16 -1 (1750 3575)(1850 3575);
WIRE 16 -1 (1550 3125)(2725 3125);
FORCEPROP 2 LAST SIG_NAME SVID_ALERT0_CPU1_R_N
J 0
(2150 3135);
DISPLAY 0.617021 (2150 3135);
PAINT ORANGE (2150 3135);
WIRE 16 -1 (2025 1675)(2025 1750);
WIRE 16 -1 (2425 1750)(2025 1750);
FORCEPROP 2 LAST SIG_NAME VR_PVCCIO_CPU1_VD12
J 0
(2110 1765);
DISPLAY 0.617021 (2110 1765);
PAINT ORANGE (2110 1765);
WIRE 16 -1 (2425 1675)(2425 1750);
WIRE 16 -1 (2425 1750)(2750 1750);
WIRE 3 682 (-1550 2450)(-1550 2350);
WIRE 3 682 (-1300 2450)(-1550 2450);
WIRE 3 682 (-1550 2350)(-1300 2350);
WIRE 3 682 (-1300 2350)(-1300 2450);
WIRE 16 -1 (2050 3575)(2675 3575);
FORCEPROP 2 LAST SIG_NAME PWRGD_PVCCIO_CPU1
J 0
(2219 3577);
DISPLAY 0.617021 (2219 3577);
PAINT ORANGE (2219 3577);
WIRE 16 -1 (-2425 1925)(-3125 1925);
FORCEPROP 2 LAST SIG_NAME VSENSE_PVCCIO_CPU1_AVSP
J 0
(-3140 1940);
DISPLAY 0.617021 (-3140 1940);
PAINT ORANGE (-3140 1940);
WIRE 3 682 (-400 2175)(-350 2175);
WIRE 3 682 (-400 2275)(-400 2175);
WIRE 3 682 (-350 2275)(-400 2275);
WIRE 3 682 (-950 700)(-200 700);
WIRE 3 682 (-950 1375)(-950 700);
WIRE 3 682 (-200 700)(-200 1375);
WIRE 3 682 (-200 1375)(-950 1375);
WIRE 16 -1 (-2425 4350)(-2425 4425);
WIRE 16 -1 (-2425 4425)(-2425 4600);
WIRE 16 -1 (-2850 4350)(-2850 4425);
WIRE 16 -1 (-2425 4425)(-2850 4425);
WIRE 16 -1 (-2850 4600)(-3200 4600);
FORCEPROP 2 LAST SIG_NAME VR_PVCCIO_CPU1_VINSEN
J 0
(-3215 4615);
DISPLAY 0.617021 (-3215 4615);
PAINT ORANGE (-3215 4615);
WIRE 16 -1 (-2850 4600)(-2850 4425);
WIRE 16 -1 (-275 2375)(-2625 2375);
FORCEPROP 2 LAST SIG_NAME SMB_VR_STBY_LVC3_SCL
J 0
(-2650 2390);
DISPLAY 0.617021 (-2650 2390);
PAINT ORANGE (-2650 2390);
WIRE 3 682 (-2450 2900)(-2000 2900);
WIRE 3 682 (-2000 2900)(-2000 2525);
WIRE 3 682 (-2450 2525)(-2450 2900);
WIRE 3 682 (-2450 2525)(-2000 2525);
WIRE 16 -1 (-275 2975)(-2625 2975);
FORCEPROP 2 LAST SIG_NAME VR_PVCCIO_CPU1_VD12
J 0
(-2575 2990);
DISPLAY 0.617021 (-2575 2990);
PAINT ORANGE (-2575 2990);
WIRE 16 -1 (-275 3125)(-2625 3125);
FORCEPROP 2 LAST SIG_NAME VR_PVCCIO_CPU1_VINSEN
J 0
(-2600 3140);
DISPLAY 0.617021 (-2600 3140);
PAINT ORANGE (-2600 3140);
DOT 1 (-2850 4425);
DOT 1 (-1550 3500);
DOT 1 (-1550 3375);
DOT 1 (-1450 2925);
DOT 1 (-850 900);
DOT 1 (750 2775);
DOT 1 (750 2525);
DOT 1 (950 3575);
DOT 1 (-2050 3925);
DOT 1 (-550 4300);
DOT 1 (-2100 3275);
DOT 1 (-1025 3225);
DOT 1 (-2075 1525);
DOT 1 (-2075 3425);
DOT 1 (-550 4675);
DOT 1 (1000 2125);
DOT 1 (2425 1750);
DOT 1 (1600 4500);
DOT 1 (1875 4500);
DOT 1 (1750 3575);
DOT 1 (1000 2075);
DOT 1 (-250 4300);
DOT 1 (-2425 4425);
DOT 1 (-2075 1925);
DOT 1 (-2075 3500);
FORCENOTE
TP FAB1 NC 0321
(725 3425) 0;
DISPLAY LEFT (725 3425);
DISPLAY 1.021277 (725 3425);
PAINT RED (725 3425);
FORCENOTE
TP FAB1 DEL NETS 0309
(800 2500) 0;
DISPLAY LEFT (800 2500);
DISPLAY 1.021277 (800 2500);
PAINT RED (800 2500);
FORCENOTE
TP FAB1 DELETE RES 0203
(-3075 3600) 0;
DISPLAY LEFT (-3075 3600);
DISPLAY 1.021277 (-3075 3600);
PAINT RED (-3075 3600);
FORCENOTE
FAIRCHILD:POP
(-3675 3625) 0;
DISPLAY LEFT (-3675 3625);
DISPLAY 0.872340 (-3675 3625);
PAINT RED (-3675 3625);
FORCENOTE
INFINEON:NOPOP
(-3675 3725) 0;
DISPLAY LEFT (-3675 3725);
DISPLAY 0.872340 (-3675 3725);
PAINT RED (-3675 3725);
FORCENOTE
RF14 & CF14
(-3675 3825) 0;
DISPLAY LEFT (-3675 3825);
DISPLAY 0.872340 (-3675 3825);
PAINT RED (-3675 3825);
FORCENOTE
TP FAB1 CO-LAY WITH FAIRCHILD PARTS 1203
(-2362 3856) 0;
DISPLAY LEFT (-2362 3856);
DISPLAY 0.638298 (-2362 3856);
PAINT RED (-2362 3856);
FORCENOTE
TP FAB3 CHANGE CAP 0912
(-2975 4500) 0;
DISPLAY LEFT (-2975 4500);
DISPLAY 0.638298 (-2975 4500);
PAINT RED (-2975 4500);
FORCENOTE
ROOM = PVCCIO_CPU1
(-3600 450) 0;
DISPLAY LEFT (-3600 450);
DISPLAY 1.021277 (-3600 450);
PAINT PURPLE (-3600 450);
FORCENOTE
TP FAB4 CHANGE RF14 TO 909OHM FOR VR FAILCHILD, SINGLE SIDE BOM 20170123
(-1450 3675) 0;
DISPLAY LEFT (-1450 3675);
DISPLAY 0.638298 (-1450 3675);
PAINT RED (-1450 3675);
FORCENOTE
TP FAB1 NC 0321
(825 2750) 0;
DISPLAY LEFT (825 2750);
DISPLAY 1.021277 (825 2750);
PAINT RED (825 2750);
FORCENOTE
TP FAB1 NC 0321
(-1075 2225) 0;
DISPLAY LEFT (-1075 2225);
DISPLAY 1.021277 (-1075 2225);
PAINT RED (-1075 2225);
FORCENOTE
TP FAB1 ADD CAP 0218
(-1975 2725) 0;
DISPLAY LEFT (-1975 2725);
DISPLAY 1.021277 (-1975 2725);
PAINT RED (-1975 2725);
FORCENOTE
TP FAB1 NC 0321
(-1050 2550) 0;
DISPLAY LEFT (-1050 2550);
DISPLAY 1.021277 (-1050 2550);
PAINT RED (-1050 2550);
FORCENOTE
TP FAB1 DEL RES 0314
(-1650 2475) 0;
DISPLAY LEFT (-1650 2475);
DISPLAY 1.021277 (-1650 2475);
PAINT RED (-1650 2475);
FORCENOTE
TP FAB1 NC 0321
(-1000 2775) 0;
DISPLAY LEFT (-1000 2775);
DISPLAY 1.021277 (-1000 2775);
PAINT RED (-1000 2775);
FORCENOTE
TP FAB1 NC 0321
(675 3025) 0;
DISPLAY LEFT (675 3025);
DISPLAY 1.021277 (675 3025);
PAINT RED (675 3025);
FORCENOTE
BOM_COST = PROC_VRD_PVCCIO_CPU1
(-3600 375) 0;
DISPLAY LEFT (-3600 375);
DISPLAY 1.021277 (-3600 375);
PAINT PURPLE (-3600 375);
FORCENOTE
TP FAB1 CHANGE R4D64 AND NOPOP R4E2 0408
(-950 650) 0;
DISPLAY LEFT (-950 650);
DISPLAY 0.638298 (-950 650);
PAINT RED (-950 650);
FORCENOTE
TP FAB3 CHANGE R4D64 AND POP R4E2 0804
(-950 600) 0;
DISPLAY LEFT (-950 600);
DISPLAY 0.638298 (-950 600);
PAINT RED (-950 600);
FORCENOTE
TP FAB1 NC 0321
(-1025 3050) 0;
DISPLAY LEFT (-1025 3050);
DISPLAY 1.021277 (-1025 3050);
PAINT RED (-1025 3050);
QUIT
